FILE_TYPE = MACRO_DRAWING;
SET COLOR_WIRE YELLOW;
SET COLOR_PROP MONO;
SET COLOR_DOT WHITE;
SET COLOR_ARC YELLOW;
SET COLOR_BODY GREEN;
SET COLOR_NOTE MONO;
SET PROP_DISPLAY VALUE;
SET PAGE_NUMBER P164;
FORCEADD RES..1
(-7400 1200);
FORCEPROP 1 LAST PACK_TYPE 0402
J 0
(-6950 1150);
DISPLAY 0.617021 (-6950 1150);
PAINT SKYBLUE (-6950 1150);
FORCEPROP 1 LAST MATERIAL CHIP
J 0
(-7100 1150);
DISPLAY 0.617021 (-7100 1150);
PAINT RED (-7100 1150);
FORCEPROP 1 LAST PART_NUMBER G21796-344
J 0
(-7550 1100);
DISPLAY 0.617021 (-7550 1100);
PAINT BLUE (-7550 1100);
FORCEPROP 1 LASTPIN (-7500 1200) $PN 1
J 0
(-7488 1212);
DISPLAY 0.617021 (-7488 1212);
PAINT ORANGE (-7488 1212);
FORCEPROP 1 LASTPIN (-7300 1200) $PN 2
J 0
(-7338 1212);
DISPLAY 0.617021 (-7338 1212);
PAINT ORANGE (-7338 1212);
FORCEPROP 1 LAST VALUE 2.7K
J 2
(-7425 1150);
DISPLAY 0.617021 (-7425 1150);
PAINT SKYBLUE (-7425 1150);
FORCEPROP 1 LAST TOLERANCE 1%
J 0
(-7325 1150);
DISPLAY 0.617021 (-7325 1150);
PAINT SKYBLUE (-7325 1150);
FORCEPROP 1 LAST WATTAGE 1/16W
J 2
(-7125 1150);
DISPLAY 0.617021 (-7125 1150);
PAINT SKYBLUE (-7125 1150);
FORCEPROP 1 LAST LOCATION R1T4
J 0
(-7625 1225);
DISPLAY 0.617021 (-7625 1225);
PAINT AQUA (-7625 1225);
FORCEPROP 2 LAST CDS_LOCATION R1T4
J 0
(-7400 1225);
DISPLAY 0.617021 (-7400 1225);
PAINT AQUA (-7400 1225);
DISPLAY INVISIBLE (-7400 1225);
FORCEPROP 0 LAST CDS_SEC 1
J 0
(-7625 1275);
PAINT MONO (-7625 1275);
DISPLAY INVISIBLE (-7625 1275);
FORCEPROP 2 LAST CDS_LIB mstr_discrete
J 0
(-7400 1200);
PAINT ORANGE (-7400 1200);
DISPLAY INVISIBLE (-7400 1200);
FORCEPROP 2 LAST SEC_TYPE 0402
J 0
(-7450 1400);
DISPLAY 1.021277 (-7450 1400);
PAINT ORANGE (-7450 1400);
DISPLAY INVISIBLE (-7450 1400);
FORCEPROP 2 LAST SEC 1
J 0
(-7450 1400);
DISPLAY 0.680851 (-7450 1400);
PAINT MONO (-7450 1400);
DISPLAY INVISIBLE (-7450 1400);
FORCEPROP 2 LAST ROOM BMC_MISC
J 0
(-7300 1275);
DISPLAY 1.021277 (-7300 1275);
PAINT ORANGE (-7300 1275);
DISPLAY INVISIBLE (-7300 1275);
FORCEPROP 2 LAST BOM_COST SM_CONTROLLER
J 0
(-7300 1325);
DISPLAY 1.021277 (-7300 1325);
PAINT ORANGE (-7300 1325);
DISPLAY INVISIBLE (-7300 1325);
FORCEPROP 1 LAST PATH I100
J 0
(-7450 1350);
DISPLAY 0.978723 (-7450 1350);
PAINT WHITE (-7450 1350);
DISPLAY INVISIBLE (-7450 1350);
FORCEADD RES..2
(-6250 925);
FORCEPROP 1 LAST PART_NUMBER G21796-026
J 0
(-6210 800);
DISPLAY 0.617021 (-6210 800);
PAINT BLUE (-6210 800);
FORCEPROP 0 LAST POP NOPOP
J 0
(-6225 700);
DISPLAY 0.808511 (-6225 700);
PAINT RED (-6225 700);
FORCEPROP 1 LAST PACK_TYPE 0402
J 0
(-6210 750);
DISPLAY 0.617021 (-6210 750);
PAINT SKYBLUE (-6210 750);
FORCEPROP 1 LAST MATERIAL CHIP
J 0
(-6210 850);
DISPLAY 0.617021 (-6210 850);
PAINT SKYBLUE (-6210 850);
FORCEPROP 1 LAST WATTAGE 1/16W
J 0
(-6210 900);
DISPLAY 0.617021 (-6210 900);
PAINT SKYBLUE (-6210 900);
FORCEPROP 1 LAST LOCATION R1T10
J 0
(-6205 1050);
DISPLAY 0.617021 (-6205 1050);
PAINT AQUA (-6205 1050);
FORCEPROP 1 LASTPIN (-6250 825) $PN 2
J 0
(-6245 835);
DISPLAY 0.617021 (-6245 835);
PAINT ORANGE (-6245 835);
FORCEPROP 1 LAST TOLERANCE 1%
J 0
(-6205 950);
DISPLAY 0.617021 (-6205 950);
PAINT SKYBLUE (-6205 950);
FORCEPROP 1 LASTPIN (-6250 1025) $PN 1
J 0
(-6245 987);
DISPLAY 0.617021 (-6245 987);
PAINT ORANGE (-6245 987);
FORCEPROP 1 LAST VALUE 1.00K
J 0
(-6205 1000);
DISPLAY 0.617021 (-6205 1000);
PAINT SKYBLUE (-6205 1000);
FORCEPROP 2 LAST CDS_LOCATION R1T10
J 0
(-6205 1050);
DISPLAY 0.617021 (-6205 1050);
PAINT AQUA (-6205 1050);
DISPLAY INVISIBLE (-6205 1050);
FORCEPROP 1 LAST PATH I101
J 0
(-6200 1100);
DISPLAY 0.978723 (-6200 1100);
PAINT WHITE (-6200 1100);
DISPLAY INVISIBLE (-6200 1100);
FORCEPROP 2 LAST ROOM BMC_MISC
J 0
(-6200 1100);
DISPLAY 1.021277 (-6200 1100);
PAINT ORANGE (-6200 1100);
DISPLAY INVISIBLE (-6200 1100);
FORCEPROP 2 LAST CDS_LIB mstr_discrete
J 0
(-6250 925);
PAINT ORANGE (-6250 925);
DISPLAY INVISIBLE (-6250 925);
FORCEPROP 2 LAST BOM_COST SM_CONTROLLER
J 0
(-6200 1150);
DISPLAY 1.021277 (-6200 1150);
PAINT ORANGE (-6200 1150);
DISPLAY INVISIBLE (-6200 1150);
FORCEPROP 2 LAST SEC_TYPE 0402
J 0
(-6200 1150);
DISPLAY 1.021277 (-6200 1150);
PAINT ORANGE (-6200 1150);
DISPLAY INVISIBLE (-6200 1150);
FORCEPROP 2 LAST SEC 1
J 0
(-6200 1150);
DISPLAY 0.680851 (-6200 1150);
PAINT MONO (-6200 1150);
DISPLAY INVISIBLE (-6200 1150);
FORCEPROP 0 LAST CDS_SEC 1
J 0
(-6200 1100);
DISPLAY INVISIBLE (-6200 1100);
FORCEADD RES..1
(-7400 1600);
FORCEPROP 1 LAST WATTAGE 1/16W
J 2
(-7125 1550);
DISPLAY 0.617021 (-7125 1550);
PAINT SKYBLUE (-7125 1550);
FORCEPROP 1 LAST TOLERANCE 1%
J 0
(-7325 1550);
DISPLAY 0.617021 (-7325 1550);
PAINT SKYBLUE (-7325 1550);
FORCEPROP 1 LASTPIN (-7300 1600) $PN 2
J 0
(-7338 1612);
DISPLAY 0.617021 (-7338 1612);
PAINT ORANGE (-7338 1612);
FORCEPROP 1 LASTPIN (-7500 1600) $PN 1
J 0
(-7488 1612);
DISPLAY 0.617021 (-7488 1612);
PAINT ORANGE (-7488 1612);
FORCEPROP 1 LAST MATERIAL EMPTY
J 0
(-7100 1550);
DISPLAY 0.617021 (-7100 1550);
PAINT RED (-7100 1550);
FORCEPROP 1 LAST PART_NUMBER G21796-344
J 0
(-7300 1625);
DISPLAY 0.617021 (-7300 1625);
PAINT BLUE (-7300 1625);
FORCEPROP 1 LAST PACK_TYPE 0402
J 0
(-6950 1550);
DISPLAY 0.617021 (-6950 1550);
PAINT SKYBLUE (-6950 1550);
FORCEPROP 1 LAST LOCATION R1T5
J 0
(-7600 1625);
DISPLAY 0.617021 (-7600 1625);
PAINT AQUA (-7600 1625);
FORCEPROP 1 LAST VALUE 2.7K
J 2
(-7425 1550);
DISPLAY 0.617021 (-7425 1550);
PAINT SKYBLUE (-7425 1550);
FORCEPROP 2 LAST SEC_TYPE 0402
J 0
(-7450 1800);
DISPLAY 1.021277 (-7450 1800);
PAINT ORANGE (-7450 1800);
DISPLAY INVISIBLE (-7450 1800);
FORCEPROP 2 LAST BOM_COST SM_CONTROLLER
J 0
(-7300 1725);
DISPLAY 1.021277 (-7300 1725);
PAINT ORANGE (-7300 1725);
DISPLAY INVISIBLE (-7300 1725);
FORCEPROP 1 LAST PATH I11
J 0
(-7450 1750);
DISPLAY 0.978723 (-7450 1750);
PAINT WHITE (-7450 1750);
DISPLAY INVISIBLE (-7450 1750);
FORCEPROP 2 LAST SEC 1
J 0
(-7450 1800);
DISPLAY 0.680851 (-7450 1800);
PAINT MONO (-7450 1800);
DISPLAY INVISIBLE (-7450 1800);
FORCEPROP 2 LAST ROOM BMC_MISC
J 0
(-7300 1675);
DISPLAY 1.021277 (-7300 1675);
PAINT ORANGE (-7300 1675);
DISPLAY INVISIBLE (-7300 1675);
FORCEPROP 2 LAST CDS_LOCATION R1T5
J 0
(-7400 1625);
DISPLAY 0.617021 (-7400 1625);
PAINT AQUA (-7400 1625);
DISPLAY INVISIBLE (-7400 1625);
FORCEPROP 2 LAST CDS_LIB mstr_discrete
J 0
(-7400 1600);
PAINT ORANGE (-7400 1600);
DISPLAY INVISIBLE (-7400 1600);
FORCEADD P3V3_STBY..1
(-7750 1750);
FORCEPROP 3 LASTPIN (-7750 1700) SIG_NAME P3V3_STBY\g
J 0
(-7740 1710);
DISPLAY 0.659574 (-7740 1710);
PAINT MONO (-7740 1710);
DISPLAY INVISIBLE (-7740 1710);
FORCEPROP 1 LAST HDL_POWER P3V3_STBY
J 0
(-8050 1625);
DISPLAY 0.872340 (-8050 1625);
PAINT ORANGE (-8050 1625);
DISPLAY INVISIBLE (-8050 1625);
FORCEPROP 1 LAST BODY_TYPE PLUMBING
J 0
(-7795 1707);
DISPLAY 0.340426 (-7795 1707);
PAINT GREEN (-7795 1707);
DISPLAY INVISIBLE (-7795 1707);
FORCEPROP 1 LAST VOLTAGE 3.3V
J 0
(-7795 1707);
DISPLAY 0.340426 (-7795 1707);
PAINT SKYBLUE (-7795 1707);
DISPLAY INVISIBLE (-7795 1707);
FORCEPROP 1 LAST SIZE 1B
J 0
(-7705 1772);
DISPLAY 0.340426 (-7705 1772);
PAINT GREEN (-7705 1772);
DISPLAY INVISIBLE (-7705 1772);
FORCEPROP 2 LAST CDS_LIB mstr_symbols
J 0
(-7750 1750);
PAINT ORANGE (-7750 1750);
DISPLAY INVISIBLE (-7750 1750);
FORCEPROP 1 LAST PATH I12
J 0
(-7705 1752);
DISPLAY 0.340426 (-7705 1752);
PAINT GREEN (-7705 1752);
DISPLAY INVISIBLE (-7705 1752);
FORCEADD OFFPAGE..2
(-4875 4275);
FORCEPROP 2 LAST $XR0 120 
J 0
(-4686 4275);
DISPLAY 0.638298 (-4686 4275);
PAINT MONO (-4686 4275);
FORCEPROP 2 LAST $XR1 147 
J 0
(-4566 4275);
DISPLAY 0.638298 (-4566 4275);
PAINT MONO (-4566 4275);
FORCEPROP 1 LAST COMMENT_BODY TRUE
J 0
(-4920 4180);
DISPLAY 0.872340 (-4920 4180);
PAINT GREEN (-4920 4180);
DISPLAY INVISIBLE (-4920 4180);
FORCEPROP 1 LAST OFFPAGE TRUE
J 0
(-4550 4150);
DISPLAY 0.872340 (-4550 4150);
PAINT GREEN (-4550 4150);
DISPLAY INVISIBLE (-4550 4150);
FORCEPROP 2 LAST PATH I15
J 0
(-4700 4350);
DISPLAY 1.021277 (-4700 4350);
PAINT ORANGE (-4700 4350);
DISPLAY INVISIBLE (-4700 4350);
FORCEPROP 2 LAST CDS_LIB mstr_standard
J 0
(-4875 4275);
PAINT ORANGE (-4875 4275);
DISPLAY INVISIBLE (-4875 4275);
FORCEADD OFFPAGE..2
(-4875 4075);
FORCEPROP 2 LAST $XR0 120 
J 0
(-4686 4075);
DISPLAY 0.638298 (-4686 4075);
PAINT MONO (-4686 4075);
FORCEPROP 2 LAST $XR1 147 
J 0
(-4566 4075);
DISPLAY 0.638298 (-4566 4075);
PAINT MONO (-4566 4075);
FORCEPROP 1 LAST COMMENT_BODY TRUE
J 0
(-4920 3980);
DISPLAY 0.872340 (-4920 3980);
PAINT GREEN (-4920 3980);
DISPLAY INVISIBLE (-4920 3980);
FORCEPROP 1 LAST OFFPAGE TRUE
J 0
(-4550 3950);
DISPLAY 0.872340 (-4550 3950);
PAINT GREEN (-4550 3950);
DISPLAY INVISIBLE (-4550 3950);
FORCEPROP 2 LAST PATH I16
J 0
(-4700 4150);
DISPLAY 1.021277 (-4700 4150);
PAINT ORANGE (-4700 4150);
DISPLAY INVISIBLE (-4700 4150);
FORCEPROP 2 LAST CDS_LIB mstr_standard
J 0
(-4875 4075);
PAINT ORANGE (-4875 4075);
DISPLAY INVISIBLE (-4875 4075);
FORCEADD OFFPAGE..2
(-4875 3875);
FORCEPROP 2 LAST $XR1 147 
J 0
(-4566 3875);
DISPLAY 0.638298 (-4566 3875);
PAINT MONO (-4566 3875);
FORCEPROP 2 LAST $XR0 120 
J 0
(-4686 3875);
DISPLAY 0.638298 (-4686 3875);
PAINT MONO (-4686 3875);
FORCEPROP 1 LAST COMMENT_BODY TRUE
J 0
(-4920 3780);
DISPLAY 0.872340 (-4920 3780);
PAINT GREEN (-4920 3780);
DISPLAY INVISIBLE (-4920 3780);
FORCEPROP 1 LAST OFFPAGE TRUE
J 0
(-4550 3750);
DISPLAY 0.872340 (-4550 3750);
PAINT GREEN (-4550 3750);
DISPLAY INVISIBLE (-4550 3750);
FORCEPROP 2 LAST PATH I17
J 0
(-4700 3950);
DISPLAY 1.021277 (-4700 3950);
PAINT ORANGE (-4700 3950);
DISPLAY INVISIBLE (-4700 3950);
FORCEPROP 2 LAST CDS_LIB mstr_standard
J 0
(-4875 3875);
PAINT ORANGE (-4875 3875);
DISPLAY INVISIBLE (-4875 3875);
FORCEADD OFFPAGE..2
(-4875 3675);
FORCEPROP 2 LAST $XR1 147 
J 0
(-4566 3675);
DISPLAY 0.638298 (-4566 3675);
PAINT MONO (-4566 3675);
FORCEPROP 2 LAST $XR0 120 
J 0
(-4686 3675);
DISPLAY 0.638298 (-4686 3675);
PAINT MONO (-4686 3675);
FORCEPROP 1 LAST COMMENT_BODY TRUE
J 0
(-4920 3580);
DISPLAY 0.872340 (-4920 3580);
PAINT GREEN (-4920 3580);
DISPLAY INVISIBLE (-4920 3580);
FORCEPROP 1 LAST OFFPAGE TRUE
J 0
(-4550 3550);
DISPLAY 0.872340 (-4550 3550);
PAINT GREEN (-4550 3550);
DISPLAY INVISIBLE (-4550 3550);
FORCEPROP 2 LAST PATH I18
J 0
(-4700 3750);
DISPLAY 1.021277 (-4700 3750);
PAINT ORANGE (-4700 3750);
DISPLAY INVISIBLE (-4700 3750);
FORCEPROP 2 LAST CDS_LIB mstr_standard
J 0
(-4875 3675);
PAINT ORANGE (-4875 3675);
DISPLAY INVISIBLE (-4875 3675);
FORCEADD OFFPAGE..2
(-5675 1600);
FORCEPROP 2 LAST $XR1 145 
J 0
(-5366 1600);
DISPLAY 0.638298 (-5366 1600);
PAINT MONO (-5366 1600);
FORCEPROP 2 LAST $XR0 119 
J 0
(-5486 1600);
DISPLAY 0.638298 (-5486 1600);
PAINT MONO (-5486 1600);
FORCEPROP 1 LAST COMMENT_BODY TRUE
J 0
(-5720 1505);
DISPLAY 0.872340 (-5720 1505);
PAINT GREEN (-5720 1505);
DISPLAY INVISIBLE (-5720 1505);
FORCEPROP 1 LAST OFFPAGE TRUE
J 0
(-5350 1475);
DISPLAY 0.872340 (-5350 1475);
PAINT GREEN (-5350 1475);
DISPLAY INVISIBLE (-5350 1475);
FORCEPROP 2 LAST CDS_LIB mstr_standard
J 0
(-5675 1600);
PAINT ORANGE (-5675 1600);
DISPLAY INVISIBLE (-5675 1600);
FORCEPROP 2 LAST PATH I2
J 0
(-5500 1675);
DISPLAY 1.021277 (-5500 1675);
PAINT ORANGE (-5500 1675);
DISPLAY INVISIBLE (-5500 1675);
FORCEADD RES..2
(-6025 3350);
FORCEPROP 1 LAST PACK_TYPE 0402
J 0
(-5985 3175);
DISPLAY 0.617021 (-5985 3175);
PAINT SKYBLUE (-5985 3175);
FORCEPROP 1 LAST WATTAGE 1/16W
J 0
(-5985 3325);
DISPLAY 0.617021 (-5985 3325);
PAINT SKYBLUE (-5985 3325);
FORCEPROP 1 LAST VALUE 1.00K
J 0
(-5980 3425);
DISPLAY 0.617021 (-5980 3425);
PAINT SKYBLUE (-5980 3425);
FORCEPROP 1 LAST LOCATION R1U17
J 0
(-5980 3475);
DISPLAY 0.617021 (-5980 3475);
PAINT AQUA (-5980 3475);
FORCEPROP 1 LAST PART_NUMBER G21796-026
J 0
(-5985 3225);
DISPLAY 0.617021 (-5985 3225);
PAINT BLUE (-5985 3225);
FORCEPROP 1 LASTPIN (-6025 3250) $PN 2
J 0
(-6020 3260);
DISPLAY 0.617021 (-6020 3260);
PAINT ORANGE (-6020 3260);
FORCEPROP 1 LASTPIN (-6025 3450) $PN 1
J 0
(-6020 3412);
DISPLAY 0.617021 (-6020 3412);
PAINT ORANGE (-6020 3412);
FORCEPROP 1 LAST MATERIAL CHIP
J 0
(-5985 3275);
DISPLAY 0.617021 (-5985 3275);
PAINT RED (-5985 3275);
FORCEPROP 1 LAST TOLERANCE 1%
J 0
(-5980 3375);
DISPLAY 0.617021 (-5980 3375);
PAINT SKYBLUE (-5980 3375);
FORCEPROP 2 LAST BOM_COST SM_CONTROLLER
J 0
(-5975 3575);
DISPLAY 1.021277 (-5975 3575);
PAINT ORANGE (-5975 3575);
DISPLAY INVISIBLE (-5975 3575);
FORCEPROP 2 LAST ROOM BMC_MISC
J 0
(-5975 3525);
DISPLAY 1.021277 (-5975 3525);
PAINT ORANGE (-5975 3525);
DISPLAY INVISIBLE (-5975 3525);
FORCEPROP 1 LAST PATH I21
J 0
(-5975 3525);
DISPLAY 0.978723 (-5975 3525);
PAINT WHITE (-5975 3525);
DISPLAY INVISIBLE (-5975 3525);
FORCEPROP 2 LAST SEC_TYPE 0402
J 0
(-5975 3575);
DISPLAY 1.021277 (-5975 3575);
PAINT ORANGE (-5975 3575);
DISPLAY INVISIBLE (-5975 3575);
FORCEPROP 2 LAST SEC 1
J 0
(-5975 3575);
DISPLAY 0.680851 (-5975 3575);
PAINT MONO (-5975 3575);
DISPLAY INVISIBLE (-5975 3575);
FORCEPROP 2 LAST CDS_LIB mstr_discrete
J 0
(-6025 3350);
PAINT ORANGE (-6025 3350);
DISPLAY INVISIBLE (-6025 3350);
FORCEPROP 2 LAST CDS_LOCATION R1U17
J 0
(-5980 3475);
DISPLAY 0.617021 (-5980 3475);
PAINT AQUA (-5980 3475);
DISPLAY INVISIBLE (-5980 3475);
FORCEADD P3V3_STBY..1
(-7525 4650);
FORCEPROP 3 LASTPIN (-7525 4600) SIG_NAME P3V3_STBY\g
J 0
(-7515 4610);
DISPLAY 0.659574 (-7515 4610);
PAINT MONO (-7515 4610);
DISPLAY INVISIBLE (-7515 4610);
FORCEPROP 1 LAST HDL_POWER P3V3_STBY
J 0
(-7825 4525);
DISPLAY 0.872340 (-7825 4525);
PAINT ORANGE (-7825 4525);
DISPLAY INVISIBLE (-7825 4525);
FORCEPROP 1 LAST BODY_TYPE PLUMBING
J 0
(-7570 4607);
DISPLAY 0.340426 (-7570 4607);
PAINT GREEN (-7570 4607);
DISPLAY INVISIBLE (-7570 4607);
FORCEPROP 1 LAST PATH I26
J 0
(-7480 4652);
DISPLAY 0.340426 (-7480 4652);
PAINT GREEN (-7480 4652);
DISPLAY INVISIBLE (-7480 4652);
FORCEPROP 1 LAST VOLTAGE 3.3V
J 0
(-7570 4607);
DISPLAY 0.340426 (-7570 4607);
PAINT SKYBLUE (-7570 4607);
DISPLAY INVISIBLE (-7570 4607);
FORCEPROP 2 LAST CDS_LIB mstr_symbols
J 0
(-7525 4650);
PAINT ORANGE (-7525 4650);
DISPLAY INVISIBLE (-7525 4650);
FORCEPROP 1 LAST SIZE 1B
J 0
(-7480 4672);
DISPLAY 0.340426 (-7480 4672);
PAINT GREEN (-7480 4672);
DISPLAY INVISIBLE (-7480 4672);
FORCEADD OFFPAGE..2
(-5675 1400);
FORCEPROP 2 LAST $XR0 119 
J 0
(-5486 1400);
DISPLAY 0.638298 (-5486 1400);
PAINT MONO (-5486 1400);
FORCEPROP 2 LAST $XR1 145 
J 0
(-5366 1400);
DISPLAY 0.638298 (-5366 1400);
PAINT MONO (-5366 1400);
FORCEPROP 1 LAST COMMENT_BODY TRUE
J 0
(-5720 1305);
DISPLAY 0.872340 (-5720 1305);
PAINT GREEN (-5720 1305);
DISPLAY INVISIBLE (-5720 1305);
FORCEPROP 1 LAST OFFPAGE TRUE
J 0
(-5350 1275);
DISPLAY 0.872340 (-5350 1275);
PAINT GREEN (-5350 1275);
DISPLAY INVISIBLE (-5350 1275);
FORCEPROP 2 LAST CDS_LIB mstr_standard
J 0
(-5675 1400);
PAINT ORANGE (-5675 1400);
DISPLAY INVISIBLE (-5675 1400);
FORCEPROP 2 LAST PATH I3
J 0
(-5500 1475);
DISPLAY 1.021277 (-5500 1475);
PAINT ORANGE (-5500 1475);
DISPLAY INVISIBLE (-5500 1475);
FORCEADD OFFPAGE..2
(-4950 4475);
FORCEPROP 2 LAST $XR0 120 
J 0
(-4761 4475);
DISPLAY 0.638298 (-4761 4475);
PAINT MONO (-4761 4475);
FORCEPROP 2 LAST $XR1 147 
J 0
(-4641 4475);
DISPLAY 0.638298 (-4641 4475);
PAINT MONO (-4641 4475);
FORCEPROP 1 LAST COMMENT_BODY TRUE
J 0
(-4995 4380);
DISPLAY 0.872340 (-4995 4380);
PAINT GREEN (-4995 4380);
DISPLAY INVISIBLE (-4995 4380);
FORCEPROP 1 LAST OFFPAGE TRUE
J 0
(-4625 4350);
DISPLAY 0.872340 (-4625 4350);
PAINT GREEN (-4625 4350);
DISPLAY INVISIBLE (-4625 4350);
FORCEPROP 2 LAST PATH I30
J 0
(-4770 4545);
DISPLAY 1.021277 (-4770 4545);
PAINT ORANGE (-4770 4545);
DISPLAY INVISIBLE (-4770 4545);
FORCEPROP 2 LAST CDS_LIB mstr_standard
J 0
(-4950 4475);
PAINT MONO (-4950 4475);
DISPLAY INVISIBLE (-4950 4475);
FORCEADD GND..1
(-6625 3050);
FORCEPROP 3 LASTPIN (-6625 3100) SIG_NAME GND\g
J 0
(-6615 3110);
DISPLAY 0.659574 (-6615 3110);
PAINT MONO (-6615 3110);
DISPLAY INVISIBLE (-6615 3110);
FORCEPROP 1 LAST HDL_POWER GND
J 0
(-6625 3200);
DISPLAY 0.872340 (-6625 3200);
PAINT GREEN (-6625 3200);
DISPLAY INVISIBLE (-6625 3200);
FORCEPROP 1 LAST BODY_TYPE PLUMBING
J 0
(-6670 3007);
DISPLAY 0.340426 (-6670 3007);
PAINT GREEN (-6670 3007);
DISPLAY INVISIBLE (-6670 3007);
FORCEPROP 1 LAST PATH I31
J 0
(-6550 3050);
DISPLAY 0.872340 (-6550 3050);
PAINT AQUA (-6550 3050);
DISPLAY INVISIBLE (-6550 3050);
FORCEPROP 1 LAST SIZE 1B
J 0
(-6550 3000);
DISPLAY 0.872340 (-6550 3000);
PAINT AQUA (-6550 3000);
DISPLAY INVISIBLE (-6550 3000);
FORCEPROP 1 LAST VOLTAGE 0.0V
J 0
(-6670 3007);
DISPLAY 0.340426 (-6670 3007);
PAINT SKYBLUE (-6670 3007);
DISPLAY INVISIBLE (-6670 3007);
FORCEPROP 2 LAST CDS_LIB mstr_symbols
J 0
(-6625 3050);
PAINT MONO (-6625 3050);
DISPLAY INVISIBLE (-6625 3050);
FORCEADD RES..2
(-6625 3350);
FORCEPROP 1 LASTPIN (-6625 3450) $PN 1
J 0
(-6620 3412);
DISPLAY 0.787234 (-6620 3412);
PAINT ORANGE (-6620 3412);
FORCEPROP 1 LASTPIN (-6625 3250) $PN 2
J 0
(-6620 3260);
DISPLAY 0.787234 (-6620 3260);
PAINT ORANGE (-6620 3260);
FORCEPROP 1 LAST PACK_TYPE 0402
J 0
(-6585 3175);
DISPLAY 0.617021 (-6585 3175);
PAINT SKYBLUE (-6585 3175);
FORCEPROP 1 LAST LOCATION R2N18
J 0
(-6580 3475);
DISPLAY 0.617021 (-6580 3475);
PAINT AQUA (-6580 3475);
FORCEPROP 1 LAST TOLERANCE 1%
J 0
(-6580 3375);
DISPLAY 0.617021 (-6580 3375);
PAINT SKYBLUE (-6580 3375);
FORCEPROP 1 LAST WATTAGE 1/16W
J 0
(-6585 3325);
DISPLAY 0.617021 (-6585 3325);
PAINT SKYBLUE (-6585 3325);
FORCEPROP 0 LAST GROUP PD_SKU_ID4
J 0
(-6600 3150);
DISPLAY 0.510638 (-6600 3150);
PAINT BROWN (-6600 3150);
DISPLAY BOTH (-6600 3150);
FORCEPROP 1 LAST MATERIAL CHIP
J 0
(-6585 3275);
DISPLAY 0.617021 (-6585 3275);
PAINT RED (-6585 3275);
FORCEPROP 1 LAST PART_NUMBER G21796-026
J 0
(-6585 3225);
DISPLAY 0.617021 (-6585 3225);
PAINT BLUE (-6585 3225);
FORCEPROP 1 LAST VALUE 1.00K
J 0
(-6580 3425);
DISPLAY 0.617021 (-6580 3425);
PAINT SKYBLUE (-6580 3425);
FORCEPROP 1 LAST PATH I32
J 0
(-6575 3525);
DISPLAY 0.978723 (-6575 3525);
PAINT WHITE (-6575 3525);
DISPLAY INVISIBLE (-6575 3525);
FORCEPROP 2 LAST CDS_LIB mstr_discrete
J 0
(-6625 3350);
PAINT MONO (-6625 3350);
DISPLAY INVISIBLE (-6625 3350);
FORCEPROP 2 LAST CDS_LOCATION R2N18
J 0
(-6580 3475);
DISPLAY 0.617021 (-6580 3475);
PAINT AQUA (-6580 3475);
DISPLAY INVISIBLE (-6580 3475);
FORCEPROP 2 LAST BOM_COST SM_CONTROLLER
J 0
(-6575 3575);
DISPLAY 1.021277 (-6575 3575);
PAINT ORANGE (-6575 3575);
DISPLAY INVISIBLE (-6575 3575);
FORCEPROP 2 LAST ROOM BMC_MISC
J 0
(-6575 3525);
DISPLAY 1.021277 (-6575 3525);
PAINT ORANGE (-6575 3525);
DISPLAY INVISIBLE (-6575 3525);
FORCEPROP 2 LAST SEC 1
J 0
(-6575 3575);
PAINT MONO (-6575 3575);
DISPLAY INVISIBLE (-6575 3575);
FORCEPROP 2 LAST SEC_TYPE 0402
J 0
(-6575 3575);
DISPLAY 1.021277 (-6575 3575);
PAINT ORANGE (-6575 3575);
DISPLAY INVISIBLE (-6575 3575);
FORCEADD RES..1
(-7175 3675);
FORCEPROP 1 LAST PACK_TYPE 0402
J 0
(-6725 3625);
DISPLAY 0.617021 (-6725 3625);
PAINT SKYBLUE (-6725 3625);
FORCEPROP 0 LAST GROUP PU_SKU_ID0
J 0
(-7050 3575);
DISPLAY 0.510638 (-7050 3575);
PAINT BROWN (-7050 3575);
DISPLAY BOTH (-7050 3575);
FORCEPROP 1 LAST MATERIAL CHIP
J 0
(-6875 3625);
DISPLAY 0.617021 (-6875 3625);
PAINT RED (-6875 3625);
FORCEPROP 1 LAST TOLERANCE 1%
J 0
(-7100 3625);
DISPLAY 0.617021 (-7100 3625);
PAINT SKYBLUE (-7100 3625);
FORCEPROP 1 LASTPIN (-7075 3675) $PN 2
J 0
(-7113 3687);
DISPLAY 0.617021 (-7113 3687);
PAINT ORANGE (-7113 3687);
FORCEPROP 1 LASTPIN (-7275 3675) $PN 1
J 0
(-7263 3687);
DISPLAY 0.617021 (-7263 3687);
PAINT ORANGE (-7263 3687);
FORCEPROP 1 LAST WATTAGE 1/16W
J 2
(-6900 3625);
DISPLAY 0.617021 (-6900 3625);
PAINT SKYBLUE (-6900 3625);
FORCEPROP 1 LAST LOCATION R1U23
J 0
(-7400 3700);
DISPLAY 0.617021 (-7400 3700);
PAINT AQUA (-7400 3700);
FORCEPROP 1 LAST VALUE 2.7K
J 2
(-7200 3625);
DISPLAY 0.617021 (-7200 3625);
PAINT SKYBLUE (-7200 3625);
FORCEPROP 1 LAST PART_NUMBER G21796-344
J 0
(-7325 3575);
DISPLAY 0.617021 (-7325 3575);
PAINT BLUE (-7325 3575);
FORCEPROP 1 LAST PATH I34
J 0
(-7225 3825);
DISPLAY 0.978723 (-7225 3825);
PAINT WHITE (-7225 3825);
DISPLAY INVISIBLE (-7225 3825);
FORCEPROP 2 LAST BOM_COST SM_CONTROLLER
J 0
(-7075 3800);
DISPLAY 1.021277 (-7075 3800);
PAINT ORANGE (-7075 3800);
DISPLAY INVISIBLE (-7075 3800);
FORCEPROP 2 LAST ROOM BMC_MISC
J 0
(-7075 3750);
DISPLAY 1.021277 (-7075 3750);
PAINT ORANGE (-7075 3750);
DISPLAY INVISIBLE (-7075 3750);
FORCEPROP 2 LAST SEC 1
J 0
(-7225 3875);
DISPLAY 0.680851 (-7225 3875);
PAINT MONO (-7225 3875);
DISPLAY INVISIBLE (-7225 3875);
FORCEPROP 2 LAST SEC_TYPE 0402
J 0
(-7225 3875);
DISPLAY 1.021277 (-7225 3875);
PAINT ORANGE (-7225 3875);
DISPLAY INVISIBLE (-7225 3875);
FORCEPROP 2 LAST CDS_LOCATION R1U23
J 0
(-7175 3700);
DISPLAY 0.617021 (-7175 3700);
PAINT AQUA (-7175 3700);
DISPLAY INVISIBLE (-7175 3700);
FORCEPROP 2 LAST CDS_LIB mstr_discrete
J 0
(-7175 3675);
PAINT ORANGE (-7175 3675);
DISPLAY INVISIBLE (-7175 3675);
FORCEPROP 0 LAST CDS_SEC 1
J 0
(-7400 3750);
PAINT MONO (-7400 3750);
DISPLAY INVISIBLE (-7400 3750);
FORCEADD RES..2
(-5725 3350);
FORCEPROP 0 LAST GROUP PD_SKU_ID1
J 0
(-5700 3075);
DISPLAY 0.510638 (-5700 3075);
PAINT BROWN (-5700 3075);
DISPLAY BOTH (-5700 3075);
FORCEPROP 1 LAST MATERIAL CHIP
J 0
(-5685 3275);
DISPLAY 0.617021 (-5685 3275);
PAINT RED (-5685 3275);
FORCEPROP 1 LAST PART_NUMBER G21796-026
J 0
(-5685 3225);
DISPLAY 0.617021 (-5685 3225);
PAINT BLUE (-5685 3225);
FORCEPROP 1 LAST PACK_TYPE 0402
J 0
(-5685 3175);
DISPLAY 0.617021 (-5685 3175);
PAINT SKYBLUE (-5685 3175);
FORCEPROP 1 LAST WATTAGE 1/16W
J 0
(-5685 3325);
DISPLAY 0.617021 (-5685 3325);
PAINT SKYBLUE (-5685 3325);
FORCEPROP 1 LAST TOLERANCE 1%
J 0
(-5680 3375);
DISPLAY 0.617021 (-5680 3375);
PAINT SKYBLUE (-5680 3375);
FORCEPROP 1 LAST VALUE 1.00K
J 0
(-5680 3425);
DISPLAY 0.617021 (-5680 3425);
PAINT SKYBLUE (-5680 3425);
FORCEPROP 1 LAST LOCATION R1U16
J 0
(-5680 3475);
DISPLAY 0.617021 (-5680 3475);
PAINT AQUA (-5680 3475);
FORCEPROP 1 LASTPIN (-5725 3250) $PN 2
J 0
(-5720 3260);
DISPLAY 0.617021 (-5720 3260);
PAINT ORANGE (-5720 3260);
FORCEPROP 1 LASTPIN (-5725 3450) $PN 1
J 0
(-5720 3412);
DISPLAY 0.617021 (-5720 3412);
PAINT ORANGE (-5720 3412);
FORCEPROP 2 LAST CDS_LOCATION R1U16
J 0
(-5680 3475);
DISPLAY 0.617021 (-5680 3475);
PAINT AQUA (-5680 3475);
DISPLAY INVISIBLE (-5680 3475);
FORCEPROP 2 LAST ROOM BMC_MISC
J 0
(-5675 3525);
DISPLAY 1.021277 (-5675 3525);
PAINT ORANGE (-5675 3525);
DISPLAY INVISIBLE (-5675 3525);
FORCEPROP 2 LAST SEC 1
J 0
(-5675 3575);
DISPLAY 0.680851 (-5675 3575);
PAINT MONO (-5675 3575);
DISPLAY INVISIBLE (-5675 3575);
FORCEPROP 2 LAST BOM_COST SM_CONTROLLER
J 0
(-5675 3575);
DISPLAY 1.021277 (-5675 3575);
PAINT ORANGE (-5675 3575);
DISPLAY INVISIBLE (-5675 3575);
FORCEPROP 2 LAST SEC_TYPE 0402
J 0
(-5675 3575);
DISPLAY 1.021277 (-5675 3575);
PAINT ORANGE (-5675 3575);
DISPLAY INVISIBLE (-5675 3575);
FORCEPROP 2 LAST CDS_LIB mstr_discrete
J 0
(-5725 3350);
PAINT ORANGE (-5725 3350);
DISPLAY INVISIBLE (-5725 3350);
FORCEPROP 1 LAST PATH I37
J 0
(-5675 3525);
DISPLAY 0.978723 (-5675 3525);
PAINT WHITE (-5675 3525);
DISPLAY INVISIBLE (-5675 3525);
FORCEADD OFFPAGE..2
(-5675 1200);
FORCEPROP 2 LAST $XR0 119 
J 0
(-5486 1200);
DISPLAY 0.638298 (-5486 1200);
PAINT MONO (-5486 1200);
FORCEPROP 2 LAST $XR1 145 
J 0
(-5366 1200);
DISPLAY 0.638298 (-5366 1200);
PAINT MONO (-5366 1200);
FORCEPROP 1 LAST COMMENT_BODY TRUE
J 0
(-5720 1105);
DISPLAY 0.872340 (-5720 1105);
PAINT GREEN (-5720 1105);
DISPLAY INVISIBLE (-5720 1105);
FORCEPROP 1 LAST OFFPAGE TRUE
J 0
(-5350 1075);
DISPLAY 0.872340 (-5350 1075);
PAINT GREEN (-5350 1075);
DISPLAY INVISIBLE (-5350 1075);
FORCEPROP 2 LAST CDS_LIB mstr_standard
J 0
(-5675 1200);
PAINT ORANGE (-5675 1200);
DISPLAY INVISIBLE (-5675 1200);
FORCEPROP 2 LAST PATH I4
J 0
(-5500 1275);
DISPLAY 1.021277 (-5500 1275);
PAINT ORANGE (-5500 1275);
DISPLAY INVISIBLE (-5500 1275);
FORCEADD RES..2
(-5425 3350);
FORCEPROP 0 LAST GROUP PD_SKU_ID0
J 0
(-5375 3150);
DISPLAY 0.510638 (-5375 3150);
PAINT BROWN (-5375 3150);
DISPLAY BOTH (-5375 3150);
FORCEPROP 1 LAST TOLERANCE 1%
J 0
(-5380 3375);
DISPLAY 0.617021 (-5380 3375);
PAINT SKYBLUE (-5380 3375);
FORCEPROP 1 LAST VALUE 1.00K
J 0
(-5380 3425);
DISPLAY 0.617021 (-5380 3425);
PAINT SKYBLUE (-5380 3425);
FORCEPROP 1 LAST LOCATION R1U18
J 0
(-5380 3475);
DISPLAY 0.617021 (-5380 3475);
PAINT AQUA (-5380 3475);
FORCEPROP 1 LAST MATERIAL CHIP
J 0
(-5385 3275);
DISPLAY 0.617021 (-5385 3275);
PAINT RED (-5385 3275);
FORCEPROP 1 LAST WATTAGE 1/16W
J 0
(-5385 3325);
DISPLAY 0.617021 (-5385 3325);
PAINT SKYBLUE (-5385 3325);
FORCEPROP 1 LAST PART_NUMBER G21796-026
J 0
(-5385 3225);
DISPLAY 0.617021 (-5385 3225);
PAINT BLUE (-5385 3225);
FORCEPROP 1 LASTPIN (-5425 3250) $PN 2
J 0
(-5420 3260);
DISPLAY 0.617021 (-5420 3260);
PAINT ORANGE (-5420 3260);
FORCEPROP 1 LAST PACK_TYPE 0402
J 0
(-5385 3175);
DISPLAY 0.617021 (-5385 3175);
PAINT SKYBLUE (-5385 3175);
FORCEPROP 1 LASTPIN (-5425 3450) $PN 1
J 0
(-5420 3412);
DISPLAY 0.617021 (-5420 3412);
PAINT ORANGE (-5420 3412);
FORCEPROP 2 LAST CDS_LOCATION R1U18
J 0
(-5380 3475);
DISPLAY 0.617021 (-5380 3475);
PAINT AQUA (-5380 3475);
DISPLAY INVISIBLE (-5380 3475);
FORCEPROP 1 LAST PATH I40
J 0
(-5375 3525);
DISPLAY 0.978723 (-5375 3525);
PAINT WHITE (-5375 3525);
DISPLAY INVISIBLE (-5375 3525);
FORCEPROP 2 LAST ROOM BMC_MISC
J 0
(-5375 3525);
DISPLAY 1.021277 (-5375 3525);
PAINT ORANGE (-5375 3525);
DISPLAY INVISIBLE (-5375 3525);
FORCEPROP 2 LAST SEC 1
J 0
(-5375 3575);
DISPLAY 0.680851 (-5375 3575);
PAINT MONO (-5375 3575);
DISPLAY INVISIBLE (-5375 3575);
FORCEPROP 2 LAST BOM_COST SM_CONTROLLER
J 0
(-5375 3575);
DISPLAY 1.021277 (-5375 3575);
PAINT ORANGE (-5375 3575);
DISPLAY INVISIBLE (-5375 3575);
FORCEPROP 2 LAST SEC_TYPE 0402
J 0
(-5375 3575);
DISPLAY 1.021277 (-5375 3575);
PAINT ORANGE (-5375 3575);
DISPLAY INVISIBLE (-5375 3575);
FORCEPROP 2 LAST CDS_LIB mstr_discrete
J 0
(-5425 3350);
PAINT ORANGE (-5425 3350);
DISPLAY INVISIBLE (-5425 3350);
FORCEADD RES..1
(-7175 4275);
FORCEPROP 1 LAST VALUE 2.7K
J 2
(-7200 4225);
DISPLAY 0.617021 (-7200 4225);
PAINT SKYBLUE (-7200 4225);
FORCEPROP 1 LASTPIN (-7275 4275) $PN 1
J 0
(-7263 4287);
DISPLAY 0.617021 (-7263 4287);
PAINT ORANGE (-7263 4287);
FORCEPROP 1 LAST LOCATION R1U21
J 0
(-7400 4300);
DISPLAY 0.617021 (-7400 4300);
PAINT AQUA (-7400 4300);
FORCEPROP 1 LASTPIN (-7075 4275) $PN 2
J 0
(-7113 4287);
DISPLAY 0.617021 (-7113 4287);
PAINT ORANGE (-7113 4287);
FORCEPROP 1 LAST TOLERANCE 1%
J 0
(-7100 4225);
DISPLAY 0.617021 (-7100 4225);
PAINT SKYBLUE (-7100 4225);
FORCEPROP 1 LAST PART_NUMBER G21796-344
J 0
(-7325 4175);
DISPLAY 0.617021 (-7325 4175);
PAINT BLUE (-7325 4175);
FORCEPROP 1 LAST WATTAGE 1/16W
J 2
(-6900 4225);
DISPLAY 0.617021 (-6900 4225);
PAINT SKYBLUE (-6900 4225);
FORCEPROP 0 LAST GROUP PU_SKU_ID3
J 0
(-7050 4175);
DISPLAY 0.510638 (-7050 4175);
PAINT BROWN (-7050 4175);
DISPLAY BOTH (-7050 4175);
FORCEPROP 1 LAST MATERIAL CHIP
J 0
(-6875 4225);
DISPLAY 0.617021 (-6875 4225);
PAINT RED (-6875 4225);
FORCEPROP 1 LAST PACK_TYPE 0402
J 0
(-6725 4225);
DISPLAY 0.617021 (-6725 4225);
PAINT SKYBLUE (-6725 4225);
FORCEPROP 1 LAST PATH I41
J 0
(-7225 4425);
DISPLAY 0.978723 (-7225 4425);
PAINT WHITE (-7225 4425);
DISPLAY INVISIBLE (-7225 4425);
FORCEPROP 0 LAST CDS_SEC 1
J 0
(-7400 4350);
PAINT MONO (-7400 4350);
DISPLAY INVISIBLE (-7400 4350);
FORCEPROP 2 LAST CDS_LIB mstr_discrete
J 0
(-7175 4275);
PAINT ORANGE (-7175 4275);
DISPLAY INVISIBLE (-7175 4275);
FORCEPROP 2 LAST SEC_TYPE 0402
J 0
(-7225 4475);
DISPLAY 1.021277 (-7225 4475);
PAINT ORANGE (-7225 4475);
DISPLAY INVISIBLE (-7225 4475);
FORCEPROP 2 LAST SEC 1
J 0
(-7225 4475);
DISPLAY 0.680851 (-7225 4475);
PAINT MONO (-7225 4475);
DISPLAY INVISIBLE (-7225 4475);
FORCEPROP 2 LAST ROOM BMC_MISC
J 0
(-7075 4350);
DISPLAY 1.021277 (-7075 4350);
PAINT ORANGE (-7075 4350);
DISPLAY INVISIBLE (-7075 4350);
FORCEPROP 2 LAST BOM_COST SM_CONTROLLER
J 0
(-7075 4400);
DISPLAY 1.021277 (-7075 4400);
PAINT ORANGE (-7075 4400);
DISPLAY INVISIBLE (-7075 4400);
FORCEPROP 2 LAST CDS_LOCATION R1U21
J 0
(-7175 4300);
DISPLAY 0.617021 (-7175 4300);
PAINT AQUA (-7175 4300);
DISPLAY INVISIBLE (-7175 4300);
FORCEADD RES..1
(-7175 3875);
FORCEPROP 1 LAST PACK_TYPE 0402
J 0
(-6725 3825);
DISPLAY 0.617021 (-6725 3825);
PAINT SKYBLUE (-6725 3825);
FORCEPROP 1 LASTPIN (-7275 3875) $PN 1
J 0
(-7263 3887);
DISPLAY 0.617021 (-7263 3887);
PAINT ORANGE (-7263 3887);
FORCEPROP 1 LAST VALUE 2.7K
J 2
(-7200 3825);
DISPLAY 0.617021 (-7200 3825);
PAINT SKYBLUE (-7200 3825);
FORCEPROP 1 LAST TOLERANCE 1%
J 0
(-7100 3825);
DISPLAY 0.617021 (-7100 3825);
PAINT SKYBLUE (-7100 3825);
FORCEPROP 1 LASTPIN (-7075 3875) $PN 2
J 0
(-7113 3887);
DISPLAY 0.617021 (-7113 3887);
PAINT ORANGE (-7113 3887);
FORCEPROP 1 LAST LOCATION R1U22
J 0
(-7400 3900);
DISPLAY 0.617021 (-7400 3900);
PAINT AQUA (-7400 3900);
FORCEPROP 1 LAST PART_NUMBER G21796-344
J 0
(-7325 3775);
DISPLAY 0.617021 (-7325 3775);
PAINT BLUE (-7325 3775);
FORCEPROP 1 LAST WATTAGE 1/16W
J 2
(-6900 3825);
DISPLAY 0.617021 (-6900 3825);
PAINT SKYBLUE (-6900 3825);
FORCEPROP 1 LAST MATERIAL CHIP
J 0
(-6875 3825);
DISPLAY 0.617021 (-6875 3825);
PAINT RED (-6875 3825);
FORCEPROP 0 LAST GROUP PU_SKU_ID1
J 0
(-7050 3775);
DISPLAY 0.510638 (-7050 3775);
PAINT BROWN (-7050 3775);
DISPLAY BOTH (-7050 3775);
FORCEPROP 2 LAST CDS_LOCATION R1U22
J 0
(-7175 3900);
DISPLAY 0.617021 (-7175 3900);
PAINT AQUA (-7175 3900);
DISPLAY INVISIBLE (-7175 3900);
FORCEPROP 0 LAST CDS_SEC 1
J 0
(-7400 3950);
PAINT MONO (-7400 3950);
DISPLAY INVISIBLE (-7400 3950);
FORCEPROP 2 LAST CDS_LIB mstr_discrete
J 0
(-7175 3875);
PAINT ORANGE (-7175 3875);
DISPLAY INVISIBLE (-7175 3875);
FORCEPROP 2 LAST SEC_TYPE 0402
J 0
(-7225 4075);
DISPLAY 1.021277 (-7225 4075);
PAINT ORANGE (-7225 4075);
DISPLAY INVISIBLE (-7225 4075);
FORCEPROP 2 LAST SEC 1
J 0
(-7225 4075);
DISPLAY 0.680851 (-7225 4075);
PAINT MONO (-7225 4075);
DISPLAY INVISIBLE (-7225 4075);
FORCEPROP 2 LAST ROOM BMC_MISC
J 0
(-7075 3950);
DISPLAY 1.021277 (-7075 3950);
PAINT ORANGE (-7075 3950);
DISPLAY INVISIBLE (-7075 3950);
FORCEPROP 2 LAST BOM_COST SM_CONTROLLER
J 0
(-7075 4000);
DISPLAY 1.021277 (-7075 4000);
PAINT ORANGE (-7075 4000);
DISPLAY INVISIBLE (-7075 4000);
FORCEPROP 1 LAST PATH I43
J 0
(-7225 4025);
DISPLAY 0.978723 (-7225 4025);
PAINT WHITE (-7225 4025);
DISPLAY INVISIBLE (-7225 4025);
FORCEADD RES..1
(-7175 4475);
FORCEPROP 1 LAST LOCATION R2N17
J 0
(-7400 4500);
DISPLAY 0.617021 (-7400 4500);
PAINT AQUA (-7400 4500);
FORCEPROP 1 LASTPIN (-7275 4475) $PN 1
J 0
(-7263 4487);
DISPLAY 0.617021 (-7263 4487);
PAINT ORANGE (-7263 4487);
FORCEPROP 1 LAST MATERIAL CHIP
J 0
(-6875 4425);
DISPLAY 0.617021 (-6875 4425);
PAINT RED (-6875 4425);
FORCEPROP 1 LASTPIN (-7075 4475) $PN 2
J 0
(-7113 4487);
DISPLAY 0.617021 (-7113 4487);
PAINT ORANGE (-7113 4487);
FORCEPROP 1 LAST WATTAGE 1/16W
J 2
(-6900 4425);
DISPLAY 0.617021 (-6900 4425);
PAINT SKYBLUE (-6900 4425);
FORCEPROP 0 LAST GROUP PU_SKU_ID4
J 0
(-7050 4375);
DISPLAY 0.510638 (-7050 4375);
PAINT BROWN (-7050 4375);
DISPLAY BOTH (-7050 4375);
FORCEPROP 1 LAST PACK_TYPE 0402
J 0
(-6725 4425);
DISPLAY 0.617021 (-6725 4425);
PAINT SKYBLUE (-6725 4425);
FORCEPROP 1 LAST VALUE 2.7K
J 2
(-7200 4425);
DISPLAY 0.617021 (-7200 4425);
PAINT SKYBLUE (-7200 4425);
FORCEPROP 1 LAST PART_NUMBER G21796-344
J 0
(-7325 4375);
DISPLAY 0.617021 (-7325 4375);
PAINT BLUE (-7325 4375);
FORCEPROP 1 LAST TOLERANCE 1%
J 0
(-7100 4425);
DISPLAY 0.617021 (-7100 4425);
PAINT SKYBLUE (-7100 4425);
FORCEPROP 1 LAST PATH I46
J 0
(-7225 4625);
DISPLAY 0.978723 (-7225 4625);
PAINT WHITE (-7225 4625);
DISPLAY INVISIBLE (-7225 4625);
FORCEPROP 2 LAST BOM_COST SM_CONTROLLER
J 0
(-7075 4600);
DISPLAY 1.021277 (-7075 4600);
PAINT ORANGE (-7075 4600);
DISPLAY INVISIBLE (-7075 4600);
FORCEPROP 2 LAST ROOM BMC_MISC
J 0
(-7075 4550);
DISPLAY 1.021277 (-7075 4550);
PAINT ORANGE (-7075 4550);
DISPLAY INVISIBLE (-7075 4550);
FORCEPROP 2 LAST SEC 1
J 0
(-7225 4675);
DISPLAY 0.680851 (-7225 4675);
PAINT MONO (-7225 4675);
DISPLAY INVISIBLE (-7225 4675);
FORCEPROP 2 LAST SEC_TYPE 0402
J 0
(-7225 4675);
DISPLAY 1.021277 (-7225 4675);
PAINT ORANGE (-7225 4675);
DISPLAY INVISIBLE (-7225 4675);
FORCEPROP 2 LAST CDS_LIB mstr_discrete
J 0
(-7175 4475);
PAINT ORANGE (-7175 4475);
DISPLAY INVISIBLE (-7175 4475);
FORCEPROP 0 LAST CDS_SEC 1
J 0
(-7400 4550);
PAINT MONO (-7400 4550);
DISPLAY INVISIBLE (-7400 4550);
FORCEPROP 2 LAST CDS_LOCATION R2N17
J 0
(-7175 4500);
DISPLAY 0.617021 (-7175 4500);
PAINT AQUA (-7175 4500);
DISPLAY INVISIBLE (-7175 4500);
FORCEADD RES..1
(-7175 4075);
FORCEPROP 1 LAST VALUE 2.7K
J 2
(-7200 4025);
DISPLAY 0.617021 (-7200 4025);
PAINT SKYBLUE (-7200 4025);
FORCEPROP 1 LASTPIN (-7275 4075) $PN 1
J 0
(-7263 4087);
DISPLAY 0.617021 (-7263 4087);
PAINT ORANGE (-7263 4087);
FORCEPROP 1 LAST LOCATION R1U24
J 0
(-7400 4100);
DISPLAY 0.617021 (-7400 4100);
PAINT AQUA (-7400 4100);
FORCEPROP 1 LAST PART_NUMBER G21796-344
J 0
(-7325 3975);
DISPLAY 0.617021 (-7325 3975);
PAINT BLUE (-7325 3975);
FORCEPROP 1 LAST TOLERANCE 1%
J 0
(-7100 4025);
DISPLAY 0.617021 (-7100 4025);
PAINT SKYBLUE (-7100 4025);
FORCEPROP 1 LASTPIN (-7075 4075) $PN 2
J 0
(-7113 4087);
DISPLAY 0.617021 (-7113 4087);
PAINT ORANGE (-7113 4087);
FORCEPROP 1 LAST WATTAGE 1/16W
J 2
(-6900 4025);
DISPLAY 0.617021 (-6900 4025);
PAINT SKYBLUE (-6900 4025);
FORCEPROP 0 LAST POP NOPOP
J 0
(-7050 3975);
DISPLAY 0.638298 (-7050 3975);
PAINT RED (-7050 3975);
FORCEPROP 1 LAST PACK_TYPE 0402
J 0
(-6725 4025);
DISPLAY 0.617021 (-6725 4025);
PAINT SKYBLUE (-6725 4025);
FORCEPROP 1 LAST MATERIAL CHIP
J 0
(-6875 4025);
DISPLAY 0.617021 (-6875 4025);
PAINT RED (-6875 4025);
FORCEPROP 2 LAST BOM_COST SM_CONTROLLER
J 0
(-7075 4200);
DISPLAY 1.021277 (-7075 4200);
PAINT ORANGE (-7075 4200);
DISPLAY INVISIBLE (-7075 4200);
FORCEPROP 2 LAST ROOM BMC_MISC
J 0
(-7075 4150);
DISPLAY 1.021277 (-7075 4150);
PAINT ORANGE (-7075 4150);
DISPLAY INVISIBLE (-7075 4150);
FORCEPROP 2 LAST SEC 1
J 0
(-7225 4275);
DISPLAY 0.680851 (-7225 4275);
PAINT MONO (-7225 4275);
DISPLAY INVISIBLE (-7225 4275);
FORCEPROP 2 LAST SEC_TYPE 0402
J 0
(-7225 4275);
DISPLAY 1.021277 (-7225 4275);
PAINT ORANGE (-7225 4275);
DISPLAY INVISIBLE (-7225 4275);
FORCEPROP 2 LAST CDS_LIB mstr_discrete
J 0
(-7175 4075);
PAINT ORANGE (-7175 4075);
DISPLAY INVISIBLE (-7175 4075);
FORCEPROP 0 LAST CDS_SEC 1
J 0
(-7400 4150);
PAINT MONO (-7400 4150);
DISPLAY INVISIBLE (-7400 4150);
FORCEPROP 1 LAST PATH I47
J 0
(-7225 4225);
DISPLAY 0.978723 (-7225 4225);
PAINT WHITE (-7225 4225);
DISPLAY INVISIBLE (-7225 4225);
FORCEPROP 2 LAST CDS_LOCATION R1U24
J 0
(-7175 4100);
DISPLAY 0.617021 (-7175 4100);
PAINT AQUA (-7175 4100);
DISPLAY INVISIBLE (-7175 4100);
FORCEADD RES..2
(-6325 3350);
FORCEPROP 1 LAST WATTAGE 1/16W
J 0
(-6285 3325);
DISPLAY 0.617021 (-6285 3325);
PAINT SKYBLUE (-6285 3325);
FORCEPROP 1 LAST TOLERANCE 1%
J 0
(-6280 3375);
DISPLAY 0.617021 (-6280 3375);
PAINT SKYBLUE (-6280 3375);
FORCEPROP 1 LAST MATERIAL CHIP
J 0
(-6285 3275);
DISPLAY 0.617021 (-6285 3275);
PAINT RED (-6285 3275);
FORCEPROP 1 LASTPIN (-6325 3250) $PN 2
J 0
(-6320 3260);
DISPLAY 0.787234 (-6320 3260);
PAINT ORANGE (-6320 3260);
FORCEPROP 1 LASTPIN (-6325 3450) $PN 1
J 0
(-6320 3412);
DISPLAY 0.787234 (-6320 3412);
PAINT ORANGE (-6320 3412);
FORCEPROP 1 LAST PACK_TYPE 0402
J 0
(-6285 3175);
DISPLAY 0.617021 (-6285 3175);
PAINT SKYBLUE (-6285 3175);
FORCEPROP 1 LAST PART_NUMBER G21796-026
J 0
(-6285 3225);
DISPLAY 0.617021 (-6285 3225);
PAINT BLUE (-6285 3225);
FORCEPROP 0 LAST GROUP PD_SKU_ID3
J 0
(-6300 3075);
DISPLAY 0.510638 (-6300 3075);
PAINT BROWN (-6300 3075);
DISPLAY BOTH (-6300 3075);
FORCEPROP 1 LAST VALUE 1.00K
J 0
(-6280 3425);
DISPLAY 0.617021 (-6280 3425);
PAINT SKYBLUE (-6280 3425);
FORCEPROP 1 LAST LOCATION R1U15
J 0
(-6280 3475);
DISPLAY 0.617021 (-6280 3475);
PAINT AQUA (-6280 3475);
FORCEPROP 1 LAST PATH I48
J 0
(-6275 3525);
DISPLAY 0.978723 (-6275 3525);
PAINT WHITE (-6275 3525);
DISPLAY INVISIBLE (-6275 3525);
FORCEPROP 2 LAST SEC_TYPE 0402
J 0
(-6275 3575);
DISPLAY 1.021277 (-6275 3575);
PAINT ORANGE (-6275 3575);
DISPLAY INVISIBLE (-6275 3575);
FORCEPROP 2 LAST SEC 1
J 0
(-6275 3575);
PAINT MONO (-6275 3575);
DISPLAY INVISIBLE (-6275 3575);
FORCEPROP 2 LAST ROOM BMC_MISC
J 0
(-6275 3525);
DISPLAY 1.021277 (-6275 3525);
PAINT ORANGE (-6275 3525);
DISPLAY INVISIBLE (-6275 3525);
FORCEPROP 2 LAST BOM_COST SM_CONTROLLER
J 0
(-6275 3575);
DISPLAY 1.021277 (-6275 3575);
PAINT ORANGE (-6275 3575);
DISPLAY INVISIBLE (-6275 3575);
FORCEPROP 2 LAST CDS_LIB mstr_discrete
J 0
(-6325 3350);
PAINT MONO (-6325 3350);
DISPLAY INVISIBLE (-6325 3350);
FORCEPROP 2 LAST CDS_LOCATION R1U15
J 0
(-6280 3475);
DISPLAY 0.617021 (-6280 3475);
PAINT AQUA (-6280 3475);
DISPLAY INVISIBLE (-6280 3475);
FORCEADD RES..1
(-7400 1400);
FORCEPROP 1 LASTPIN (-7500 1400) $PN 1
J 0
(-7488 1412);
DISPLAY 0.617021 (-7488 1412);
PAINT ORANGE (-7488 1412);
FORCEPROP 1 LASTPIN (-7300 1400) $PN 2
J 0
(-7338 1412);
DISPLAY 0.617021 (-7338 1412);
PAINT ORANGE (-7338 1412);
FORCEPROP 1 LAST VALUE 2.7K
J 2
(-7425 1350);
DISPLAY 0.617021 (-7425 1350);
PAINT SKYBLUE (-7425 1350);
FORCEPROP 1 LAST TOLERANCE 1%
J 0
(-7325 1350);
DISPLAY 0.617021 (-7325 1350);
PAINT SKYBLUE (-7325 1350);
FORCEPROP 1 LAST PACK_TYPE 0402
J 0
(-6950 1350);
DISPLAY 0.617021 (-6950 1350);
PAINT SKYBLUE (-6950 1350);
FORCEPROP 1 LAST LOCATION R1T6
J 0
(-7625 1425);
DISPLAY 0.617021 (-7625 1425);
PAINT AQUA (-7625 1425);
FORCEPROP 1 LAST PART_NUMBER G21796-344
J 0
(-7550 1300);
DISPLAY 0.617021 (-7550 1300);
PAINT BLUE (-7550 1300);
FORCEPROP 1 LAST WATTAGE 1/16W
J 2
(-7125 1350);
DISPLAY 0.617021 (-7125 1350);
PAINT SKYBLUE (-7125 1350);
FORCEPROP 1 LAST MATERIAL CHIP
J 0
(-7100 1350);
DISPLAY 0.617021 (-7100 1350);
PAINT RED (-7100 1350);
FORCEPROP 1 LAST PATH I51
J 0
(-7450 1550);
DISPLAY 0.978723 (-7450 1550);
PAINT WHITE (-7450 1550);
DISPLAY INVISIBLE (-7450 1550);
FORCEPROP 0 LAST CDS_SEC 1
J 0
(-7625 1475);
PAINT MONO (-7625 1475);
DISPLAY INVISIBLE (-7625 1475);
FORCEPROP 2 LAST CDS_LIB mstr_discrete
J 0
(-7400 1400);
PAINT ORANGE (-7400 1400);
DISPLAY INVISIBLE (-7400 1400);
FORCEPROP 2 LAST SEC_TYPE 0402
J 0
(-7450 1600);
DISPLAY 1.021277 (-7450 1600);
PAINT ORANGE (-7450 1600);
DISPLAY INVISIBLE (-7450 1600);
FORCEPROP 2 LAST SEC 1
J 0
(-7450 1600);
DISPLAY 0.680851 (-7450 1600);
PAINT MONO (-7450 1600);
DISPLAY INVISIBLE (-7450 1600);
FORCEPROP 2 LAST ROOM BMC_MISC
J 0
(-7300 1475);
DISPLAY 1.021277 (-7300 1475);
PAINT ORANGE (-7300 1475);
DISPLAY INVISIBLE (-7300 1475);
FORCEPROP 2 LAST BOM_COST SM_CONTROLLER
J 0
(-7300 1525);
DISPLAY 1.021277 (-7300 1525);
PAINT ORANGE (-7300 1525);
DISPLAY INVISIBLE (-7300 1525);
FORCEPROP 2 LAST CDS_LOCATION R1T6
J 0
(-7400 1425);
DISPLAY 0.617021 (-7400 1425);
PAINT AQUA (-7400 1425);
DISPLAY INVISIBLE (-7400 1425);
FORCEADD RES..2
(-6550 925);
FORCEPROP 1 LAST PACK_TYPE 0402
J 0
(-6510 750);
DISPLAY 0.617021 (-6510 750);
PAINT SKYBLUE (-6510 750);
FORCEPROP 1 LAST LOCATION R1T12
J 0
(-6505 1050);
DISPLAY 0.617021 (-6505 1050);
PAINT AQUA (-6505 1050);
FORCEPROP 1 LASTPIN (-6550 825) $PN 2
J 0
(-6545 835);
DISPLAY 0.617021 (-6545 835);
PAINT ORANGE (-6545 835);
FORCEPROP 0 LAST POP NOPOP
J 0
(-6525 700);
DISPLAY 0.808511 (-6525 700);
PAINT RED (-6525 700);
FORCEPROP 1 LAST MATERIAL CHIP
J 0
(-6510 850);
DISPLAY 0.617021 (-6510 850);
PAINT SKYBLUE (-6510 850);
FORCEPROP 1 LAST WATTAGE 1/16W
J 0
(-6510 900);
DISPLAY 0.617021 (-6510 900);
PAINT SKYBLUE (-6510 900);
FORCEPROP 1 LAST TOLERANCE 1%
J 0
(-6505 950);
DISPLAY 0.617021 (-6505 950);
PAINT SKYBLUE (-6505 950);
FORCEPROP 1 LASTPIN (-6550 1025) $PN 1
J 0
(-6545 987);
DISPLAY 0.617021 (-6545 987);
PAINT ORANGE (-6545 987);
FORCEPROP 1 LAST VALUE 1.00K
J 0
(-6505 1000);
DISPLAY 0.617021 (-6505 1000);
PAINT SKYBLUE (-6505 1000);
FORCEPROP 1 LAST PART_NUMBER G21796-026
J 0
(-6510 800);
DISPLAY 0.617021 (-6510 800);
PAINT BLUE (-6510 800);
FORCEPROP 2 LAST CDS_LOCATION R1T12
J 0
(-6505 1050);
DISPLAY 0.617021 (-6505 1050);
PAINT AQUA (-6505 1050);
DISPLAY INVISIBLE (-6505 1050);
FORCEPROP 1 LAST PATH I53
J 0
(-6500 1100);
DISPLAY 0.978723 (-6500 1100);
PAINT WHITE (-6500 1100);
DISPLAY INVISIBLE (-6500 1100);
FORCEPROP 2 LAST ROOM BMC_MISC
J 0
(-6500 1100);
DISPLAY 1.021277 (-6500 1100);
PAINT ORANGE (-6500 1100);
DISPLAY INVISIBLE (-6500 1100);
FORCEPROP 2 LAST CDS_LIB mstr_discrete
J 0
(-6550 925);
PAINT ORANGE (-6550 925);
DISPLAY INVISIBLE (-6550 925);
FORCEPROP 2 LAST BOM_COST SM_CONTROLLER
J 0
(-6500 1150);
DISPLAY 1.021277 (-6500 1150);
PAINT ORANGE (-6500 1150);
DISPLAY INVISIBLE (-6500 1150);
FORCEPROP 2 LAST SEC_TYPE 0402
J 0
(-6500 1150);
DISPLAY 1.021277 (-6500 1150);
PAINT ORANGE (-6500 1150);
DISPLAY INVISIBLE (-6500 1150);
FORCEPROP 2 LAST SEC 1
J 0
(-6500 1150);
DISPLAY 0.680851 (-6500 1150);
PAINT MONO (-6500 1150);
DISPLAY INVISIBLE (-6500 1150);
FORCEPROP 0 LAST CDS_SEC 1
J 0
(-6500 1100);
DISPLAY INVISIBLE (-6500 1100);
FORCEADD GND..1
(-1750 3175);
FORCEPROP 3 LASTPIN (-1750 3225) SIG_NAME GND\g
J 0
(-1740 3235);
DISPLAY 0.659574 (-1740 3235);
PAINT MONO (-1740 3235);
DISPLAY INVISIBLE (-1740 3235);
FORCEPROP 1 LAST PATH I55
J 0
(-1675 3175);
DISPLAY 0.872340 (-1675 3175);
PAINT AQUA (-1675 3175);
DISPLAY INVISIBLE (-1675 3175);
FORCEPROP 1 LAST VOLTAGE 0.0V
J 0
(-1795 3132);
DISPLAY 0.340426 (-1795 3132);
PAINT GREEN (-1795 3132);
DISPLAY INVISIBLE (-1795 3132);
FORCEPROP 1 LAST SIZE 1B
J 0
(-1675 3125);
DISPLAY 0.872340 (-1675 3125);
PAINT AQUA (-1675 3125);
DISPLAY INVISIBLE (-1675 3125);
FORCEPROP 2 LAST CDS_LIB mstr_symbols
J 0
(-1750 3175);
PAINT MONO (-1750 3175);
DISPLAY INVISIBLE (-1750 3175);
FORCEPROP 1 LAST BODY_TYPE PLUMBING
J 0
(-1795 3132);
DISPLAY 0.340426 (-1795 3132);
PAINT GREEN (-1795 3132);
DISPLAY INVISIBLE (-1795 3132);
FORCEPROP 1 LAST HDL_POWER GND
J 0
(-1750 3325);
DISPLAY 0.872340 (-1750 3325);
PAINT GREEN (-1750 3325);
DISPLAY INVISIBLE (-1750 3325);
FORCEADD OFFPAGE..4
(-850 3400);
FORCEPROP 2 LAST $XR0 167 
J 0
(-634 3400);
DISPLAY 0.638298 (-634 3400);
PAINT MONO (-634 3400);
FORCEPROP 2 LAST $XR1 184 
J 0
(-514 3400);
DISPLAY 0.638298 (-514 3400);
PAINT MONO (-514 3400);
FORCEPROP 2 LAST $XR2 191 
J 0
(-394 3400);
DISPLAY 0.638298 (-394 3400);
PAINT MONO (-394 3400);
FORCEPROP 2 LAST CDS_LIB mstr_standard
J 0
(-850 3400);
PAINT MONO (-850 3400);
DISPLAY INVISIBLE (-850 3400);
FORCEPROP 1 LAST OFFPAGE TRUE
J 0
(-525 3275);
PAINT GREEN (-525 3275);
DISPLAY INVISIBLE (-525 3275);
FORCEPROP 1 LAST COMMENT_BODY TRUE
J 0
(-875 3300);
DISPLAY 1.404255 (-875 3300);
PAINT PEACH (-875 3300);
DISPLAY INVISIBLE (-875 3300);
FORCEPROP 2 LAST PATH I56
J 0
(-375 3450);
DISPLAY 1.021277 (-375 3450);
PAINT ORANGE (-375 3450);
DISPLAY INVISIBLE (-375 3450);
FORCEADD P3V3_STBY..1
(-3400 4150);
FORCEPROP 3 LASTPIN (-3400 4100) SIG_NAME P3V3_STBY\g
J 0
(-3390 4110);
DISPLAY 0.659574 (-3390 4110);
PAINT MONO (-3390 4110);
DISPLAY INVISIBLE (-3390 4110);
FORCEPROP 2 LAST CDS_LIB mstr_symbols
J 0
(-3400 4150);
PAINT MONO (-3400 4150);
DISPLAY INVISIBLE (-3400 4150);
FORCEPROP 1 LAST SIZE 1B
J 0
(-3355 4172);
DISPLAY 0.340426 (-3355 4172);
PAINT GREEN (-3355 4172);
DISPLAY INVISIBLE (-3355 4172);
FORCEPROP 1 LAST VOLTAGE 3.3V
J 0
(-3445 4107);
DISPLAY 0.340426 (-3445 4107);
PAINT GREEN (-3445 4107);
DISPLAY INVISIBLE (-3445 4107);
FORCEPROP 1 LAST BODY_TYPE PLUMBING
J 0
(-3445 4107);
DISPLAY 0.340426 (-3445 4107);
PAINT GREEN (-3445 4107);
DISPLAY INVISIBLE (-3445 4107);
FORCEPROP 1 LAST HDL_POWER P3V3_STBY
J 0
(-3700 4025);
DISPLAY 0.872340 (-3700 4025);
PAINT ORANGE (-3700 4025);
DISPLAY INVISIBLE (-3700 4025);
FORCEPROP 1 LAST PATH I65
J 0
(-3355 4152);
DISPLAY 0.340426 (-3355 4152);
PAINT GREEN (-3355 4152);
DISPLAY INVISIBLE (-3355 4152);
FORCEADD CAP_A..1
(-3400 3900);
FORCEPROP 1 LAST VOLTAGE 16V
J 0
(-3350 3900);
DISPLAY 0.617021 (-3350 3900);
PAINT SKYBLUE (-3350 3900);
FORCEPROP 1 LAST VALUE 0.1UF
J 0
(-3350 3950);
DISPLAY 0.617021 (-3350 3950);
PAINT SKYBLUE (-3350 3950);
FORCEPROP 1 LAST LOCATION C6W14
J 0
(-3350 4000);
DISPLAY 0.617021 (-3350 4000);
PAINT AQUA (-3350 4000);
FORCEPROP 1 LAST PACK_TYPE 0402V
J 0
(-3350 3700);
DISPLAY 0.617021 (-3350 3700);
PAINT SKYBLUE (-3350 3700);
FORCEPROP 1 LAST MATERIAL X7R
J 0
(-3350 3800);
DISPLAY 0.617021 (-3350 3800);
PAINT SKYBLUE (-3350 3800);
FORCEPROP 1 LAST TOLERANCE 10%
J 0
(-3350 3850);
DISPLAY 0.617021 (-3350 3850);
PAINT SKYBLUE (-3350 3850);
FORCEPROP 1 LASTPIN (-3400 4000) $PN 1
J 0
(-3390 3980);
DISPLAY 0.617021 (-3390 3980);
PAINT ORANGE (-3390 3980);
FORCEPROP 1 LASTPIN (-3400 3800) $PN 2
J 0
(-3390 3780);
DISPLAY 0.617021 (-3390 3780);
PAINT ORANGE (-3390 3780);
FORCEPROP 1 LAST PART_NUMBER A36096-030
J 0
(-3350 3750);
DISPLAY 0.617021 (-3350 3750);
PAINT BLUE (-3350 3750);
FORCEPROP 2 LAST CDS_LOCATION C6W14
J 0
(-3350 4000);
DISPLAY 0.617021 (-3350 4000);
PAINT AQUA (-3350 4000);
DISPLAY INVISIBLE (-3350 4000);
FORCEPROP 2 LAST SEC 1
J 0
(-3350 4125);
DISPLAY 0.680851 (-3350 4125);
PAINT MONO (-3350 4125);
DISPLAY INVISIBLE (-3350 4125);
FORCEPROP 2 LAST SEC_TYPE 0402V
J 0
(-3350 4125);
DISPLAY 1.021277 (-3350 4125);
PAINT ORANGE (-3350 4125);
DISPLAY INVISIBLE (-3350 4125);
FORCEPROP 2 LAST ROOM VDDQ_KLM_PWR_VR
J 0
(-3350 4050);
DISPLAY 1.361702 (-3350 4050);
PAINT ORANGE (-3350 4050);
DISPLAY INVISIBLE (-3350 4050);
FORCEPROP 2 LAST CDS_SEC 1
J 0
(-3350 4050);
PAINT ORANGE (-3350 4050);
DISPLAY INVISIBLE (-3350 4050);
FORCEPROP 2 LAST CDS_LIB dev_discrete
J 0
(-3400 3900);
PAINT ORANGE (-3400 3900);
DISPLAY INVISIBLE (-3400 3900);
FORCEPROP 1 LAST PATH I66
J 0
(-3350 4050);
DISPLAY 0.978723 (-3350 4050);
PAINT WHITE (-3350 4050);
DISPLAY INVISIBLE (-3350 4050);
FORCEADD GND..1
(-3400 3700);
FORCEPROP 3 LASTPIN (-3400 3750) SIG_NAME GND\g
J 0
(-3390 3760);
DISPLAY 0.659574 (-3390 3760);
PAINT MONO (-3390 3760);
DISPLAY INVISIBLE (-3390 3760);
FORCEPROP 1 LAST VOLTAGE 0.0V
J 0
(-3445 3657);
DISPLAY 0.340426 (-3445 3657);
PAINT GREEN (-3445 3657);
DISPLAY INVISIBLE (-3445 3657);
FORCEPROP 1 LAST SIZE 1B
J 0
(-3325 3650);
DISPLAY 1.170213 (-3325 3650);
PAINT AQUA (-3325 3650);
DISPLAY INVISIBLE (-3325 3650);
FORCEPROP 2 LAST CDS_LIB mstr_symbols
J 0
(-3400 3700);
PAINT MONO (-3400 3700);
DISPLAY INVISIBLE (-3400 3700);
FORCEPROP 1 LAST BODY_TYPE PLUMBING
J 0
(-3445 3657);
DISPLAY 0.340426 (-3445 3657);
PAINT GREEN (-3445 3657);
DISPLAY INVISIBLE (-3445 3657);
FORCEPROP 1 LAST HDL_POWER GND
J 0
(-3400 3850);
DISPLAY 1.170213 (-3400 3850);
PAINT GREEN (-3400 3850);
DISPLAY INVISIBLE (-3400 3850);
FORCEPROP 1 LAST PATH I67
J 0
(-3325 3700);
DISPLAY 0.872340 (-3325 3700);
PAINT AQUA (-3325 3700);
DISPLAY INVISIBLE (-3325 3700);
FORCEADD RES..2
(-6850 925);
FORCEPROP 1 LAST PART_NUMBER G21796-026
J 0
(-6810 800);
DISPLAY 0.617021 (-6810 800);
PAINT BLUE (-6810 800);
FORCEPROP 1 LAST WATTAGE 1/16W
J 0
(-6810 900);
DISPLAY 0.617021 (-6810 900);
PAINT SKYBLUE (-6810 900);
FORCEPROP 1 LAST TOLERANCE 1%
J 0
(-6805 950);
DISPLAY 0.617021 (-6805 950);
PAINT SKYBLUE (-6805 950);
FORCEPROP 1 LAST MATERIAL CHIP
J 0
(-6810 850);
DISPLAY 0.617021 (-6810 850);
PAINT SKYBLUE (-6810 850);
FORCEPROP 1 LAST VALUE 1.00K
J 0
(-6805 1000);
DISPLAY 0.617021 (-6805 1000);
PAINT SKYBLUE (-6805 1000);
FORCEPROP 1 LASTPIN (-6850 1025) $PN 1
J 0
(-6845 987);
DISPLAY 0.617021 (-6845 987);
PAINT ORANGE (-6845 987);
FORCEPROP 1 LAST PACK_TYPE 0402
J 0
(-6810 750);
DISPLAY 0.617021 (-6810 750);
PAINT SKYBLUE (-6810 750);
FORCEPROP 1 LASTPIN (-6850 825) $PN 2
J 0
(-6845 835);
DISPLAY 0.617021 (-6845 835);
PAINT ORANGE (-6845 835);
FORCEPROP 1 LAST LOCATION R1T11
J 0
(-6805 1050);
DISPLAY 0.617021 (-6805 1050);
PAINT AQUA (-6805 1050);
FORCEPROP 2 LAST SEC 1
J 0
(-6800 1150);
DISPLAY 0.680851 (-6800 1150);
PAINT MONO (-6800 1150);
DISPLAY INVISIBLE (-6800 1150);
FORCEPROP 2 LAST BOM_COST SM_CONTROLLER
J 0
(-6800 1150);
DISPLAY 1.021277 (-6800 1150);
PAINT ORANGE (-6800 1150);
DISPLAY INVISIBLE (-6800 1150);
FORCEPROP 2 LAST SEC_TYPE 0402
J 0
(-6800 1150);
DISPLAY 1.021277 (-6800 1150);
PAINT ORANGE (-6800 1150);
DISPLAY INVISIBLE (-6800 1150);
FORCEPROP 2 LAST ROOM BMC_MISC
J 0
(-6800 1100);
DISPLAY 1.021277 (-6800 1100);
PAINT ORANGE (-6800 1100);
DISPLAY INVISIBLE (-6800 1100);
FORCEPROP 1 LAST PATH I7
J 0
(-6800 1100);
DISPLAY 0.978723 (-6800 1100);
PAINT WHITE (-6800 1100);
DISPLAY INVISIBLE (-6800 1100);
FORCEPROP 2 LAST CDS_LOCATION R1T11
J 0
(-6805 1050);
DISPLAY 0.617021 (-6805 1050);
PAINT AQUA (-6805 1050);
DISPLAY INVISIBLE (-6805 1050);
FORCEPROP 2 LAST CDS_LIB mstr_discrete
J 0
(-6850 925);
PAINT ORANGE (-6850 925);
DISPLAY INVISIBLE (-6850 925);
FORCEADD RES..2
(-1650 1800);
FORCEPROP 1 LASTPIN (-1650 1700) $PN 2
J 0
(-1645 1710);
DISPLAY 0.787234 (-1645 1710);
PAINT ORANGE (-1645 1710);
FORCEPROP 1 LAST PACK_TYPE 0402
J 0
(-1610 1625);
DISPLAY 0.617021 (-1610 1625);
PAINT SKYBLUE (-1610 1625);
FORCEPROP 1 LAST PART_NUMBER G21796-072
J 0
(-1610 1675);
DISPLAY 0.617021 (-1610 1675);
PAINT BLUE (-1610 1675);
FORCEPROP 1 LAST MATERIAL EMPTY
J 0
(-1610 1725);
DISPLAY 0.617021 (-1610 1725);
PAINT RED (-1610 1725);
FORCEPROP 1 LAST WATTAGE 1/16W
J 0
(-1610 1775);
DISPLAY 0.617021 (-1610 1775);
PAINT SKYBLUE (-1610 1775);
FORCEPROP 1 LASTPIN (-1650 1900) $PN 1
J 0
(-1645 1862);
DISPLAY 0.787234 (-1645 1862);
PAINT ORANGE (-1645 1862);
FORCEPROP 1 LAST TOLERANCE 1%
J 0
(-1605 1825);
DISPLAY 0.617021 (-1605 1825);
PAINT SKYBLUE (-1605 1825);
FORCEPROP 1 LAST VALUE 4.75K
J 0
(-1605 1875);
DISPLAY 0.617021 (-1605 1875);
PAINT SKYBLUE (-1605 1875);
FORCEPROP 1 LAST LOCATION R6W47
J 0
(-1605 1925);
DISPLAY 0.617021 (-1605 1925);
PAINT AQUA (-1605 1925);
FORCEPROP 0 LAST CDS_LOCATION R6W47
J 0
(-1600 1975);
DISPLAY INVISIBLE (-1600 1975);
FORCEPROP 1 LAST PATH I76
J 0
(-1600 1975);
DISPLAY 0.978723 (-1600 1975);
PAINT WHITE (-1600 1975);
DISPLAY INVISIBLE (-1600 1975);
FORCEPROP 2 LAST CDS_LIB mstr_discrete
J 0
(-1650 1800);
PAINT MONO (-1650 1800);
DISPLAY INVISIBLE (-1650 1800);
FORCEPROP 0 LAST ROOM HOT_SWAP
J 0
(-1600 2025);
DISPLAY 1.021277 (-1600 2025);
PAINT ORANGE (-1600 2025);
DISPLAY INVISIBLE (-1600 2025);
FORCEPROP 0 LAST NO_XNET_CONNECTION 1
J 0
(-1600 2025);
PAINT MONO (-1600 2025);
DISPLAY INVISIBLE (-1600 2025);
FORCEPROP 0 LAST SEC 1
J 0
(-1600 1975);
DISPLAY 0.680851 (-1600 1975);
PAINT MONO (-1600 1975);
DISPLAY INVISIBLE (-1600 1975);
FORCEPROP 2 LAST SEC_TYPE 0402
J 0
(-1600 2025);
DISPLAY 1.021277 (-1600 2025);
PAINT ORANGE (-1600 2025);
DISPLAY INVISIBLE (-1600 2025);
FORCEPROP 0 LAST CDS_SEC 1
J 0
(-1600 1975);
DISPLAY INVISIBLE (-1600 1975);
FORCEADD RES..2
R 2
(-1650 2350);
FORCEPROP 1 LAST VALUE 4.75K
J 0
(-1595 2425);
DISPLAY 0.617021 (-1595 2425);
PAINT SKYBLUE (-1595 2425);
FORCEPROP 1 LASTPIN (-1650 2450) $PN 1
J 2
(-1655 2412);
DISPLAY 0.787234 (-1655 2412);
PAINT ORANGE (-1655 2412);
FORCEPROP 1 LAST TOLERANCE 1%
J 0
(-1595 2375);
DISPLAY 0.617021 (-1595 2375);
PAINT SKYBLUE (-1595 2375);
FORCEPROP 1 LASTPIN (-1650 2250) $PN 2
J 2
(-1655 2260);
DISPLAY 0.787234 (-1655 2260);
PAINT ORANGE (-1655 2260);
FORCEPROP 1 LAST MATERIAL CHIP
J 0
(-1590 2275);
DISPLAY 0.617021 (-1590 2275);
PAINT SKYBLUE (-1590 2275);
FORCEPROP 1 LAST WATTAGE 1/16W
J 0
(-1590 2325);
DISPLAY 0.617021 (-1590 2325);
PAINT SKYBLUE (-1590 2325);
FORCEPROP 1 LAST PACK_TYPE 0402
J 0
(-1590 2175);
DISPLAY 0.617021 (-1590 2175);
PAINT SKYBLUE (-1590 2175);
FORCEPROP 1 LAST PART_NUMBER G21796-072
J 0
(-1590 2225);
DISPLAY 0.617021 (-1590 2225);
PAINT BLUE (-1590 2225);
FORCEPROP 1 LAST LOCATION R6W44
J 0
(-1595 2475);
DISPLAY 0.617021 (-1595 2475);
PAINT AQUA (-1595 2475);
FORCEPROP 1 LAST PATH I78
J 2
(-1700 2525);
DISPLAY 0.978723 (-1700 2525);
PAINT WHITE (-1700 2525);
DISPLAY INVISIBLE (-1700 2525);
FORCEPROP 2 LAST SEC_TYPE 0402
J 0
(-1700 2575);
DISPLAY 1.021277 (-1700 2575);
PAINT ORANGE (-1700 2575);
DISPLAY INVISIBLE (-1700 2575);
FORCEPROP 0 LAST SEC 1
J 0
(-1675 2525);
DISPLAY 0.680851 (-1675 2525);
PAINT MONO (-1675 2525);
DISPLAY INVISIBLE (-1675 2525);
FORCEPROP 0 LAST ROOM CPU_FANS
J 0
(-1675 2575);
DISPLAY 1.021277 (-1675 2575);
PAINT ORANGE (-1675 2575);
DISPLAY INVISIBLE (-1675 2575);
FORCEPROP 0 LAST BOM_COST SM_THERM
J 0
(-1675 2675);
DISPLAY 1.021277 (-1675 2675);
PAINT ORANGE (-1675 2675);
DISPLAY INVISIBLE (-1675 2675);
FORCEPROP 2 LAST CDS_LIB mstr_discrete
J 0
(-1650 2350);
PAINT MONO (-1650 2350);
DISPLAY INVISIBLE (-1650 2350);
FORCEADD P3V3_STBY..1
(-2350 2650);
FORCEPROP 3 LASTPIN (-2350 2600) SIG_NAME P3V3_STBY\g
J 0
(-2340 2610);
DISPLAY 0.659574 (-2340 2610);
PAINT MONO (-2340 2610);
DISPLAY INVISIBLE (-2340 2610);
FORCEPROP 1 LAST PATH I81
J 0
(-2305 2652);
DISPLAY 0.340426 (-2305 2652);
PAINT GREEN (-2305 2652);
DISPLAY INVISIBLE (-2305 2652);
FORCEPROP 1 LAST HDL_POWER P3V3_STBY
J 0
(-2650 2525);
DISPLAY 0.872340 (-2650 2525);
PAINT ORANGE (-2650 2525);
DISPLAY INVISIBLE (-2650 2525);
FORCEPROP 1 LAST BODY_TYPE PLUMBING
J 0
(-2395 2607);
DISPLAY 0.340426 (-2395 2607);
PAINT GREEN (-2395 2607);
DISPLAY INVISIBLE (-2395 2607);
FORCEPROP 1 LAST SIZE 1B
J 0
(-2305 2672);
DISPLAY 0.340426 (-2305 2672);
PAINT GREEN (-2305 2672);
DISPLAY INVISIBLE (-2305 2672);
FORCEPROP 2 LAST CDS_LIB mstr_symbols
J 0
(-2350 2650);
PAINT MONO (-2350 2650);
DISPLAY INVISIBLE (-2350 2650);
FORCEPROP 1 LAST VOLTAGE 3.3V
J 0
(-2395 2607);
DISPLAY 0.340426 (-2395 2607);
PAINT GREEN (-2395 2607);
DISPLAY INVISIBLE (-2395 2607);
FORCEADD GND..1
(-1650 1600);
FORCEPROP 3 LASTPIN (-1650 1650) SIG_NAME GND\g
J 0
(-1640 1660);
DISPLAY 0.659574 (-1640 1660);
PAINT MONO (-1640 1660);
DISPLAY INVISIBLE (-1640 1660);
FORCEPROP 1 LAST PATH I82
J 0
(-1575 1600);
DISPLAY 0.872340 (-1575 1600);
PAINT AQUA (-1575 1600);
DISPLAY INVISIBLE (-1575 1600);
FORCEPROP 1 LAST HDL_POWER GND
J 0
(-1650 1750);
DISPLAY 0.872340 (-1650 1750);
PAINT GREEN (-1650 1750);
DISPLAY INVISIBLE (-1650 1750);
FORCEPROP 1 LAST BODY_TYPE PLUMBING
J 0
(-1695 1557);
DISPLAY 0.340426 (-1695 1557);
PAINT GREEN (-1695 1557);
DISPLAY INVISIBLE (-1695 1557);
FORCEPROP 1 LAST SIZE 1B
J 0
(-1575 1550);
DISPLAY 0.872340 (-1575 1550);
PAINT AQUA (-1575 1550);
DISPLAY INVISIBLE (-1575 1550);
FORCEPROP 2 LAST CDS_LIB mstr_symbols
J 0
(-1650 1600);
PAINT MONO (-1650 1600);
DISPLAY INVISIBLE (-1650 1600);
FORCEPROP 1 LAST VOLTAGE 0.0V
J 0
(-1695 1557);
DISPLAY 0.340426 (-1695 1557);
PAINT GREEN (-1695 1557);
DISPLAY INVISIBLE (-1695 1557);
FORCEADD GND..1
(-2000 1600);
FORCEPROP 3 LASTPIN (-2000 1650) SIG_NAME GND\g
J 0
(-1990 1660);
DISPLAY 0.659574 (-1990 1660);
PAINT MONO (-1990 1660);
DISPLAY INVISIBLE (-1990 1660);
FORCEPROP 1 LAST PATH I84
J 0
(-1925 1600);
DISPLAY 0.872340 (-1925 1600);
PAINT AQUA (-1925 1600);
DISPLAY INVISIBLE (-1925 1600);
FORCEPROP 1 LAST HDL_POWER GND
J 0
(-2000 1750);
DISPLAY 0.872340 (-2000 1750);
PAINT GREEN (-2000 1750);
DISPLAY INVISIBLE (-2000 1750);
FORCEPROP 1 LAST BODY_TYPE PLUMBING
J 0
(-2045 1557);
DISPLAY 0.340426 (-2045 1557);
PAINT GREEN (-2045 1557);
DISPLAY INVISIBLE (-2045 1557);
FORCEPROP 1 LAST VOLTAGE 0.0V
J 0
(-2045 1557);
DISPLAY 0.340426 (-2045 1557);
PAINT GREEN (-2045 1557);
DISPLAY INVISIBLE (-2045 1557);
FORCEPROP 2 LAST CDS_LIB mstr_symbols
J 0
(-2000 1600);
PAINT MONO (-2000 1600);
DISPLAY INVISIBLE (-2000 1600);
FORCEPROP 1 LAST SIZE 1B
J 0
(-1925 1550);
DISPLAY 0.872340 (-1925 1550);
PAINT AQUA (-1925 1550);
DISPLAY INVISIBLE (-1925 1550);
FORCEADD GND..1
(-2350 1600);
FORCEPROP 3 LASTPIN (-2350 1650) SIG_NAME GND\g
J 0
(-2340 1660);
DISPLAY 0.659574 (-2340 1660);
PAINT MONO (-2340 1660);
DISPLAY INVISIBLE (-2340 1660);
FORCEPROP 1 LAST PATH I86
J 0
(-2275 1600);
DISPLAY 0.872340 (-2275 1600);
PAINT AQUA (-2275 1600);
DISPLAY INVISIBLE (-2275 1600);
FORCEPROP 1 LAST HDL_POWER GND
J 0
(-2350 1750);
DISPLAY 0.872340 (-2350 1750);
PAINT GREEN (-2350 1750);
DISPLAY INVISIBLE (-2350 1750);
FORCEPROP 1 LAST BODY_TYPE PLUMBING
J 0
(-2395 1557);
DISPLAY 0.340426 (-2395 1557);
PAINT GREEN (-2395 1557);
DISPLAY INVISIBLE (-2395 1557);
FORCEPROP 1 LAST SIZE 1B
J 0
(-2275 1550);
DISPLAY 0.872340 (-2275 1550);
PAINT AQUA (-2275 1550);
DISPLAY INVISIBLE (-2275 1550);
FORCEPROP 2 LAST CDS_LIB mstr_symbols
J 0
(-2350 1600);
PAINT MONO (-2350 1600);
DISPLAY INVISIBLE (-2350 1600);
FORCEPROP 1 LAST VOLTAGE 0.0V
J 0
(-2395 1557);
DISPLAY 0.340426 (-2395 1557);
PAINT GREEN (-2395 1557);
DISPLAY INVISIBLE (-2395 1557);
FORCEADD RES..2
R 2
(-1000 3750);
FORCEPROP 1 LASTPIN (-1000 3650) $PN 2
J 2
(-1005 3660);
DISPLAY 0.787234 (-1005 3660);
PAINT ORANGE (-1005 3660);
FORCEPROP 1 LASTPIN (-1000 3850) $PN 1
J 2
(-1005 3812);
DISPLAY 0.787234 (-1005 3812);
PAINT ORANGE (-1005 3812);
FORCEPROP 1 LAST VALUE 4.75K
J 0
(-945 3825);
DISPLAY 0.617021 (-945 3825);
PAINT SKYBLUE (-945 3825);
FORCEPROP 1 LAST LOCATION R6W41
J 0
(-945 3875);
DISPLAY 0.617021 (-945 3875);
PAINT AQUA (-945 3875);
FORCEPROP 1 LAST MATERIAL CHIP
J 0
(-940 3675);
DISPLAY 0.617021 (-940 3675);
PAINT SKYBLUE (-940 3675);
FORCEPROP 1 LAST TOLERANCE 1%
J 0
(-945 3775);
DISPLAY 0.617021 (-945 3775);
PAINT SKYBLUE (-945 3775);
FORCEPROP 1 LAST WATTAGE 1/16W
J 0
(-940 3725);
DISPLAY 0.617021 (-940 3725);
PAINT SKYBLUE (-940 3725);
FORCEPROP 1 LAST PART_NUMBER G21796-072
J 0
(-940 3625);
DISPLAY 0.617021 (-940 3625);
PAINT BLUE (-940 3625);
FORCEPROP 1 LAST PACK_TYPE 0402
J 0
(-940 3575);
DISPLAY 0.617021 (-940 3575);
PAINT SKYBLUE (-940 3575);
FORCEPROP 0 LAST CDS_SEC 1
J 0
(-925 3925);
DISPLAY INVISIBLE (-925 3925);
FORCEPROP 2 LAST SEC_TYPE 0402
J 0
(-1050 3975);
DISPLAY 1.021277 (-1050 3975);
PAINT ORANGE (-1050 3975);
DISPLAY INVISIBLE (-1050 3975);
FORCEPROP 0 LAST SEC 1
J 0
(-1025 3925);
DISPLAY 0.680851 (-1025 3925);
PAINT MONO (-1025 3925);
DISPLAY INVISIBLE (-1025 3925);
FORCEPROP 0 LAST ROOM CPU_FANS
J 0
(-1025 3975);
DISPLAY 1.021277 (-1025 3975);
PAINT ORANGE (-1025 3975);
DISPLAY INVISIBLE (-1025 3975);
FORCEPROP 0 LAST BOM_COST SM_THERM
J 0
(-1025 4075);
DISPLAY 1.021277 (-1025 4075);
PAINT ORANGE (-1025 4075);
DISPLAY INVISIBLE (-1025 4075);
FORCEPROP 2 LAST CDS_LIB mstr_discrete
J 0
(-1000 3750);
PAINT MONO (-1000 3750);
DISPLAY INVISIBLE (-1000 3750);
FORCEPROP 1 LAST PATH I87
J 2
(-1050 3925);
DISPLAY 0.978723 (-1050 3925);
PAINT WHITE (-1050 3925);
DISPLAY INVISIBLE (-1050 3925);
FORCEPROP 0 LAST CDS_LOCATION R6W41
J 0
(-925 3925);
DISPLAY INVISIBLE (-925 3925);
FORCEADD P3V3_STBY..1
(-1000 3950);
FORCEPROP 3 LASTPIN (-1000 3900) SIG_NAME P3V3_STBY\g
J 0
(-990 3910);
DISPLAY 0.659574 (-990 3910);
PAINT MONO (-990 3910);
DISPLAY INVISIBLE (-990 3910);
FORCEPROP 1 LAST HDL_POWER P3V3_STBY
J 0
(-1300 3825);
DISPLAY 0.872340 (-1300 3825);
PAINT ORANGE (-1300 3825);
DISPLAY INVISIBLE (-1300 3825);
FORCEPROP 1 LAST BODY_TYPE PLUMBING
J 0
(-1045 3907);
DISPLAY 0.340426 (-1045 3907);
PAINT GREEN (-1045 3907);
DISPLAY INVISIBLE (-1045 3907);
FORCEPROP 2 LAST CDS_LIB mstr_symbols
J 0
(-1000 3950);
PAINT MONO (-1000 3950);
DISPLAY INVISIBLE (-1000 3950);
FORCEPROP 1 LAST SIZE 1B
J 0
(-955 3972);
DISPLAY 0.340426 (-955 3972);
PAINT GREEN (-955 3972);
DISPLAY INVISIBLE (-955 3972);
FORCEPROP 1 LAST VOLTAGE 3.3V
J 0
(-1045 3907);
DISPLAY 0.340426 (-1045 3907);
PAINT GREEN (-1045 3907);
DISPLAY INVISIBLE (-1045 3907);
FORCEPROP 1 LAST PATH I88
J 0
(-955 3952);
DISPLAY 0.340426 (-955 3952);
PAINT GREEN (-955 3952);
DISPLAY INVISIBLE (-955 3952);
FORCEADD OFFPAGE..1
(-3150 3500);
FORCEPROP 2 LAST $XR0 181 
J 0
(-3402 3500);
DISPLAY 0.638298 (-3402 3500);
PAINT MONO (-3402 3500);
FORCEPROP 2 LAST $XR1 119 
J 0
(-3522 3500);
DISPLAY 0.638298 (-3522 3500);
PAINT MONO (-3522 3500);
FORCEPROP 2 LAST PATH I89
J 0
(-3425 3550);
DISPLAY 1.021277 (-3425 3550);
PAINT ORANGE (-3425 3550);
DISPLAY INVISIBLE (-3425 3550);
FORCEPROP 2 LAST CDS_LIB mstr_standard
J 0
(-3150 3500);
PAINT ORANGE (-3150 3500);
DISPLAY INVISIBLE (-3150 3500);
FORCEPROP 1 LAST COMMENT_BODY TRUE
J 0
(-3025 3400);
DISPLAY 1.170213 (-3025 3400);
PAINT PEACH (-3025 3400);
DISPLAY INVISIBLE (-3025 3400);
FORCEPROP 1 LAST OFFPAGE TRUE
J 0
(-2825 3375);
DISPLAY 1.170213 (-2825 3375);
PAINT GREEN (-2825 3375);
DISPLAY INVISIBLE (-2825 3375);
FORCEADD GND..1
(-6850 625);
FORCEPROP 3 LASTPIN (-6850 675) SIG_NAME GND\g
J 0
(-6840 685);
DISPLAY 0.659574 (-6840 685);
PAINT MONO (-6840 685);
DISPLAY INVISIBLE (-6840 685);
FORCEPROP 1 LAST HDL_POWER GND
J 0
(-6850 775);
DISPLAY 0.872340 (-6850 775);
PAINT GREEN (-6850 775);
DISPLAY INVISIBLE (-6850 775);
FORCEPROP 1 LAST BODY_TYPE PLUMBING
J 0
(-6895 582);
DISPLAY 0.340426 (-6895 582);
PAINT GREEN (-6895 582);
DISPLAY INVISIBLE (-6895 582);
FORCEPROP 2 LAST CDS_LIB mstr_symbols
J 0
(-6850 625);
PAINT ORANGE (-6850 625);
DISPLAY INVISIBLE (-6850 625);
FORCEPROP 1 LAST PATH I9
J 0
(-6775 625);
DISPLAY 0.872340 (-6775 625);
PAINT AQUA (-6775 625);
DISPLAY INVISIBLE (-6775 625);
FORCEPROP 1 LAST SIZE 1B
J 0
(-6775 575);
DISPLAY 0.872340 (-6775 575);
PAINT AQUA (-6775 575);
DISPLAY INVISIBLE (-6775 575);
FORCEPROP 1 LAST VOLTAGE 0.0V
J 0
(-6895 582);
DISPLAY 0.340426 (-6895 582);
PAINT SKYBLUE (-6895 582);
DISPLAY INVISIBLE (-6895 582);
FORCEADD OFFPAGE..1
(-3150 3550);
FORCEPROP 2 LAST $XR0 181 
J 0
(-3402 3550);
DISPLAY 0.638298 (-3402 3550);
PAINT MONO (-3402 3550);
FORCEPROP 2 LAST $XR1 119 
J 0
(-3522 3550);
DISPLAY 0.638298 (-3522 3550);
PAINT MONO (-3522 3550);
FORCEPROP 2 LAST PATH I90
J 0
(-3425 3600);
DISPLAY 1.021277 (-3425 3600);
PAINT ORANGE (-3425 3600);
DISPLAY INVISIBLE (-3425 3600);
FORCEPROP 1 LAST OFFPAGE TRUE
J 0
(-2825 3425);
DISPLAY 1.170213 (-2825 3425);
PAINT GREEN (-2825 3425);
DISPLAY INVISIBLE (-2825 3425);
FORCEPROP 1 LAST COMMENT_BODY TRUE
J 0
(-3025 3450);
DISPLAY 1.170213 (-3025 3450);
PAINT PEACH (-3025 3450);
DISPLAY INVISIBLE (-3025 3450);
FORCEPROP 2 LAST CDS_LIB mstr_standard
J 0
(-3150 3550);
PAINT ORANGE (-3150 3550);
DISPLAY INVISIBLE (-3150 3550);
FORCEADD OFFPAGE..1
(-3150 3600);
FORCEPROP 2 LAST $XR0 181 
J 0
(-3402 3600);
DISPLAY 0.638298 (-3402 3600);
PAINT MONO (-3402 3600);
FORCEPROP 2 LAST $XR1 119 
J 0
(-3522 3600);
DISPLAY 0.638298 (-3522 3600);
PAINT MONO (-3522 3600);
FORCEPROP 2 LAST PATH I91
J 0
(-3425 3650);
DISPLAY 1.021277 (-3425 3650);
PAINT ORANGE (-3425 3650);
DISPLAY INVISIBLE (-3425 3650);
FORCEPROP 2 LAST CDS_LIB mstr_standard
J 0
(-3150 3600);
PAINT ORANGE (-3150 3600);
DISPLAY INVISIBLE (-3150 3600);
FORCEPROP 1 LAST COMMENT_BODY TRUE
J 0
(-3025 3500);
DISPLAY 1.170213 (-3025 3500);
PAINT PEACH (-3025 3500);
DISPLAY INVISIBLE (-3025 3500);
FORCEPROP 1 LAST OFFPAGE TRUE
J 0
(-2825 3475);
DISPLAY 1.170213 (-2825 3475);
PAINT GREEN (-2825 3475);
DISPLAY INVISIBLE (-2825 3475);
FORCEADD OFFPAGE..5
(-3150 3450);
FORCEPROP 2 LAST $XR0 119 
J 0
(-3405 3450);
DISPLAY 0.638298 (-3405 3450);
PAINT MONO (-3405 3450);
FORCEPROP 2 LAST $XR1 156 
J 0
(-3525 3450);
DISPLAY 0.638298 (-3525 3450);
PAINT MONO (-3525 3450);
FORCEPROP 2 LAST PATH I92
J 0
(-3425 3500);
DISPLAY 1.021277 (-3425 3500);
PAINT ORANGE (-3425 3500);
DISPLAY INVISIBLE (-3425 3500);
FORCEPROP 1 LAST COMMENT_BODY TRUE
J 0
(-3050 3375);
DISPLAY 0.872340 (-3050 3375);
PAINT GREEN (-3050 3375);
DISPLAY INVISIBLE (-3050 3375);
FORCEPROP 1 LAST OFFPAGE TRUE
J 0
(-2825 3325);
DISPLAY 0.872340 (-2825 3325);
PAINT GREEN (-2825 3325);
DISPLAY INVISIBLE (-2825 3325);
FORCEPROP 2 LAST CDS_LIB mstr_standard
J 0
(-3150 3450);
PAINT ORANGE (-3150 3450);
DISPLAY INVISIBLE (-3150 3450);
FORCEADD RES..2
R 2
(-2000 1800);
FORCEPROP 1 LAST VALUE 4.75K
J 0
(-1970 1875);
DISPLAY 0.617021 (-1970 1875);
PAINT SKYBLUE (-1970 1875);
FORCEPROP 1 LAST WATTAGE 1/16W
J 0
(-1965 1775);
DISPLAY 0.617021 (-1965 1775);
PAINT SKYBLUE (-1965 1775);
FORCEPROP 1 LASTPIN (-2000 1900) $PN 1
J 2
(-2005 1862);
DISPLAY 0.787234 (-2005 1862);
PAINT ORANGE (-2005 1862);
FORCEPROP 1 LASTPIN (-2000 1700) $PN 2
J 2
(-2005 1710);
DISPLAY 0.787234 (-2005 1710);
PAINT ORANGE (-2005 1710);
FORCEPROP 1 LAST TOLERANCE 1%
J 0
(-1970 1825);
DISPLAY 0.617021 (-1970 1825);
PAINT SKYBLUE (-1970 1825);
FORCEPROP 1 LAST LOCATION R6W46
J 0
(-1970 1925);
DISPLAY 0.617021 (-1970 1925);
PAINT AQUA (-1970 1925);
FORCEPROP 1 LAST MATERIAL CHIP
J 0
(-1965 1725);
DISPLAY 0.617021 (-1965 1725);
PAINT SKYBLUE (-1965 1725);
FORCEPROP 1 LAST PART_NUMBER G21796-072
J 0
(-1965 1675);
DISPLAY 0.617021 (-1965 1675);
PAINT BLUE (-1965 1675);
FORCEPROP 1 LAST PACK_TYPE 0402
J 0
(-1965 1625);
DISPLAY 0.617021 (-1965 1625);
PAINT SKYBLUE (-1965 1625);
FORCEPROP 2 LAST SEC_TYPE 0402
J 0
(-2050 2025);
DISPLAY 1.021277 (-2050 2025);
PAINT ORANGE (-2050 2025);
DISPLAY INVISIBLE (-2050 2025);
FORCEPROP 0 LAST SEC 1
J 0
(-2025 1975);
DISPLAY 0.680851 (-2025 1975);
PAINT MONO (-2025 1975);
DISPLAY INVISIBLE (-2025 1975);
FORCEPROP 0 LAST BOM_COST SM_THERM
J 0
(-2025 2125);
DISPLAY 1.021277 (-2025 2125);
PAINT ORANGE (-2025 2125);
DISPLAY INVISIBLE (-2025 2125);
FORCEPROP 0 LAST ROOM CPU_FANS
J 0
(-2025 2025);
DISPLAY 1.021277 (-2025 2025);
PAINT ORANGE (-2025 2025);
DISPLAY INVISIBLE (-2025 2025);
FORCEPROP 2 LAST CDS_LIB mstr_discrete
J 0
(-2000 1800);
PAINT MONO (-2000 1800);
DISPLAY INVISIBLE (-2000 1800);
FORCEPROP 1 LAST PATH I93
J 2
(-2050 1975);
DISPLAY 0.978723 (-2050 1975);
PAINT WHITE (-2050 1975);
DISPLAY INVISIBLE (-2050 1975);
FORCEADD RES..2
R 2
(-2350 1800);
FORCEPROP 1 LAST TOLERANCE 1%
J 0
(-2320 1825);
DISPLAY 0.617021 (-2320 1825);
PAINT SKYBLUE (-2320 1825);
FORCEPROP 1 LASTPIN (-2350 1700) $PN 2
J 2
(-2355 1710);
DISPLAY 0.787234 (-2355 1710);
PAINT ORANGE (-2355 1710);
FORCEPROP 1 LASTPIN (-2350 1900) $PN 1
J 2
(-2355 1862);
DISPLAY 0.787234 (-2355 1862);
PAINT ORANGE (-2355 1862);
FORCEPROP 1 LAST LOCATION R6W45
J 0
(-2320 1925);
DISPLAY 0.617021 (-2320 1925);
PAINT AQUA (-2320 1925);
FORCEPROP 1 LAST VALUE 4.75K
J 0
(-2320 1875);
DISPLAY 0.617021 (-2320 1875);
PAINT SKYBLUE (-2320 1875);
FORCEPROP 1 LAST WATTAGE 1/16W
J 0
(-2315 1775);
DISPLAY 0.617021 (-2315 1775);
PAINT SKYBLUE (-2315 1775);
FORCEPROP 1 LAST MATERIAL CHIP
J 0
(-2315 1725);
DISPLAY 0.617021 (-2315 1725);
PAINT SKYBLUE (-2315 1725);
FORCEPROP 1 LAST PART_NUMBER G21796-072
J 0
(-2315 1675);
DISPLAY 0.617021 (-2315 1675);
PAINT BLUE (-2315 1675);
FORCEPROP 1 LAST PACK_TYPE 0402
J 0
(-2315 1625);
DISPLAY 0.617021 (-2315 1625);
PAINT SKYBLUE (-2315 1625);
FORCEPROP 2 LAST SEC_TYPE 0402
J 0
(-2400 2025);
DISPLAY 1.021277 (-2400 2025);
PAINT ORANGE (-2400 2025);
DISPLAY INVISIBLE (-2400 2025);
FORCEPROP 0 LAST SEC 1
J 0
(-2375 1975);
DISPLAY 0.680851 (-2375 1975);
PAINT MONO (-2375 1975);
DISPLAY INVISIBLE (-2375 1975);
FORCEPROP 0 LAST BOM_COST SM_THERM
J 0
(-2375 2125);
DISPLAY 1.021277 (-2375 2125);
PAINT ORANGE (-2375 2125);
DISPLAY INVISIBLE (-2375 2125);
FORCEPROP 0 LAST ROOM CPU_FANS
J 0
(-2375 2025);
DISPLAY 1.021277 (-2375 2025);
PAINT ORANGE (-2375 2025);
DISPLAY INVISIBLE (-2375 2025);
FORCEPROP 2 LAST CDS_LIB mstr_discrete
J 0
(-2350 1800);
PAINT MONO (-2350 1800);
DISPLAY INVISIBLE (-2350 1800);
FORCEPROP 1 LAST PATH I94
J 2
(-2400 1975);
DISPLAY 0.978723 (-2400 1975);
PAINT WHITE (-2400 1975);
DISPLAY INVISIBLE (-2400 1975);
FORCEADD RES..2
(-2350 2350);
FORCEPROP 1 LASTPIN (-2350 2450) $PN 1
J 0
(-2345 2412);
DISPLAY 0.787234 (-2345 2412);
PAINT ORANGE (-2345 2412);
FORCEPROP 1 LAST WATTAGE 1/16W
J 0
(-2310 2325);
DISPLAY 0.617021 (-2310 2325);
PAINT SKYBLUE (-2310 2325);
FORCEPROP 1 LASTPIN (-2350 2250) $PN 2
J 0
(-2345 2260);
DISPLAY 0.787234 (-2345 2260);
PAINT ORANGE (-2345 2260);
FORCEPROP 1 LAST LOCATION R6W42
J 0
(-2305 2475);
DISPLAY 0.617021 (-2305 2475);
PAINT AQUA (-2305 2475);
FORCEPROP 1 LAST VALUE 4.75K
J 0
(-2305 2425);
DISPLAY 0.617021 (-2305 2425);
PAINT SKYBLUE (-2305 2425);
FORCEPROP 1 LAST TOLERANCE 1%
J 0
(-2305 2375);
DISPLAY 0.617021 (-2305 2375);
PAINT SKYBLUE (-2305 2375);
FORCEPROP 1 LAST MATERIAL EMPTY
J 0
(-2310 2275);
DISPLAY 0.617021 (-2310 2275);
PAINT RED (-2310 2275);
FORCEPROP 1 LAST PART_NUMBER G21796-072
J 0
(-2310 2225);
DISPLAY 0.617021 (-2310 2225);
PAINT BLUE (-2310 2225);
FORCEPROP 1 LAST PACK_TYPE 0402
J 0
(-2310 2175);
DISPLAY 0.617021 (-2310 2175);
PAINT SKYBLUE (-2310 2175);
FORCEPROP 0 LAST CDS_SEC 1
J 0
(-2300 2525);
DISPLAY INVISIBLE (-2300 2525);
FORCEPROP 0 LAST NO_XNET_CONNECTION 1
J 0
(-2300 2575);
PAINT MONO (-2300 2575);
DISPLAY INVISIBLE (-2300 2575);
FORCEPROP 0 LAST ROOM HOT_SWAP
J 0
(-2300 2575);
DISPLAY 1.021277 (-2300 2575);
PAINT ORANGE (-2300 2575);
DISPLAY INVISIBLE (-2300 2575);
FORCEPROP 2 LAST CDS_LIB mstr_discrete
J 0
(-2350 2350);
PAINT MONO (-2350 2350);
DISPLAY INVISIBLE (-2350 2350);
FORCEPROP 2 LAST SEC 1
J 0
(-2300 2575);
DISPLAY 0.680851 (-2300 2575);
PAINT MONO (-2300 2575);
DISPLAY INVISIBLE (-2300 2575);
FORCEPROP 2 LAST SEC_TYPE 0402
J 0
(-2300 2575);
DISPLAY 1.021277 (-2300 2575);
PAINT ORANGE (-2300 2575);
DISPLAY INVISIBLE (-2300 2575);
FORCEPROP 1 LAST PATH I95
J 0
(-2300 2525);
DISPLAY 0.978723 (-2300 2525);
PAINT WHITE (-2300 2525);
DISPLAY INVISIBLE (-2300 2525);
FORCEPROP 0 LAST CDS_LOCATION R6W42
J 0
(-2300 2525);
DISPLAY INVISIBLE (-2300 2525);
FORCEADD RES..2
(-2000 2350);
FORCEPROP 1 LAST PART_NUMBER G21796-072
J 0
(-2010 2225);
DISPLAY 0.617021 (-2010 2225);
PAINT BLUE (-2010 2225);
FORCEPROP 1 LAST LOCATION R6W43
J 0
(-1955 2475);
DISPLAY 0.617021 (-1955 2475);
PAINT AQUA (-1955 2475);
FORCEPROP 1 LASTPIN (-2000 2450) $PN 1
J 0
(-1995 2412);
DISPLAY 0.787234 (-1995 2412);
PAINT ORANGE (-1995 2412);
FORCEPROP 1 LAST TOLERANCE 1%
J 0
(-1955 2375);
DISPLAY 0.617021 (-1955 2375);
PAINT SKYBLUE (-1955 2375);
FORCEPROP 1 LASTPIN (-2000 2250) $PN 2
J 0
(-1995 2260);
DISPLAY 0.787234 (-1995 2260);
PAINT ORANGE (-1995 2260);
FORCEPROP 1 LAST MATERIAL EMPTY
J 0
(-1960 2275);
DISPLAY 0.617021 (-1960 2275);
PAINT RED (-1960 2275);
FORCEPROP 1 LAST WATTAGE 1/16W
J 0
(-1960 2325);
DISPLAY 0.617021 (-1960 2325);
PAINT SKYBLUE (-1960 2325);
FORCEPROP 1 LAST VALUE 4.75K
J 0
(-1955 2425);
DISPLAY 0.617021 (-1955 2425);
PAINT SKYBLUE (-1955 2425);
FORCEPROP 1 LAST PACK_TYPE 0402
J 0
(-1960 2175);
DISPLAY 0.617021 (-1960 2175);
PAINT SKYBLUE (-1960 2175);
FORCEPROP 0 LAST CDS_SEC 1
J 0
(-1950 2525);
DISPLAY INVISIBLE (-1950 2525);
FORCEPROP 2 LAST CDS_LIB mstr_discrete
J 0
(-2000 2350);
PAINT MONO (-2000 2350);
DISPLAY INVISIBLE (-2000 2350);
FORCEPROP 0 LAST NO_XNET_CONNECTION 1
J 0
(-1950 2575);
PAINT MONO (-1950 2575);
DISPLAY INVISIBLE (-1950 2575);
FORCEPROP 0 LAST ROOM HOT_SWAP
J 0
(-1950 2575);
DISPLAY 1.021277 (-1950 2575);
PAINT ORANGE (-1950 2575);
DISPLAY INVISIBLE (-1950 2575);
FORCEPROP 0 LAST SEC 1
J 0
(-1950 2525);
DISPLAY 0.680851 (-1950 2525);
PAINT MONO (-1950 2525);
DISPLAY INVISIBLE (-1950 2525);
FORCEPROP 2 LAST SEC_TYPE 0402
J 0
(-1950 2575);
DISPLAY 1.021277 (-1950 2575);
PAINT ORANGE (-1950 2575);
DISPLAY INVISIBLE (-1950 2575);
FORCEPROP 1 LAST PATH I96
J 0
(-1950 2525);
DISPLAY 0.978723 (-1950 2525);
PAINT WHITE (-1950 2525);
DISPLAY INVISIBLE (-1950 2525);
FORCEPROP 0 LAST CDS_LOCATION R6W43
J 0
(-1950 2525);
DISPLAY INVISIBLE (-1950 2525);
FORCEADD PCA9554PWR-GP..1
(-2150 3500);
FORCEPROP 2 LASTPIN (-1800 3550) $PN 13
J 0
(-1790 3560);
DISPLAY 0.808511 (-1790 3560);
PAINT ORANGE (-1790 3560);
FORCEPROP 2 LASTPIN (-1800 3250) $PN 8
J 0
(-1790 3260);
DISPLAY 0.808511 (-1790 3260);
PAINT ORANGE (-1790 3260);
FORCEPROP 2 LASTPIN (-1800 3650) $PN 3
J 0
(-1790 3660);
DISPLAY 0.808511 (-1790 3660);
PAINT ORANGE (-1790 3660);
FORCEPROP 2 LASTPIN (-1800 3700) $PN 2
J 0
(-1790 3710);
DISPLAY 0.808511 (-1790 3710);
PAINT ORANGE (-1790 3710);
FORCEPROP 2 LASTPIN (-1800 3750) $PN 1
J 0
(-1790 3760);
DISPLAY 0.808511 (-1790 3760);
PAINT ORANGE (-1790 3760);
FORCEPROP 2 LASTPIN (-2500 3250) $PN 12
J 2
(-2510 3260);
DISPLAY 0.808511 (-2510 3260);
PAINT ORANGE (-2510 3260);
FORCEPROP 2 LASTPIN (-2500 3750) $PN 16
J 2
(-2510 3760);
DISPLAY 0.808511 (-2510 3760);
PAINT ORANGE (-2510 3760);
FORCEPROP 1 LAST LOCATION U6W11
J 0
(-2350 3825);
DISPLAY 0.617021 (-2350 3825);
PAINT GREEN (-2350 3825);
FORCEPROP 2 LASTPIN (-2500 3600) $PN 4
J 2
(-2510 3610);
DISPLAY 0.808511 (-2510 3610);
PAINT ORANGE (-2510 3610);
FORCEPROP 2 LASTPIN (-2500 3550) $PN 5
J 2
(-2510 3560);
DISPLAY 0.808511 (-2510 3560);
PAINT ORANGE (-2510 3560);
FORCEPROP 2 LASTPIN (-2500 3500) $PN 6
J 2
(-2510 3510);
DISPLAY 0.808511 (-2510 3510);
PAINT ORANGE (-2510 3510);
FORCEPROP 2 LASTPIN (-2500 3450) $PN 7
J 2
(-2510 3460);
DISPLAY 0.808511 (-2510 3460);
PAINT ORANGE (-2510 3460);
FORCEPROP 2 LASTPIN (-1800 3450) $PN 15
J 0
(-1790 3460);
DISPLAY 0.808511 (-1790 3460);
PAINT ORANGE (-1790 3460);
FORCEPROP 2 LASTPIN (-1800 3400) $PN 14
J 0
(-1790 3410);
DISPLAY 0.808511 (-1790 3410);
PAINT ORANGE (-1790 3410);
FORCEPROP 2 LASTPIN (-2500 3400) $PN 9
J 2
(-2510 3410);
DISPLAY 0.808511 (-2510 3410);
PAINT ORANGE (-2510 3410);
FORCEPROP 2 LASTPIN (-2500 3350) $PN 10
J 2
(-2510 3360);
DISPLAY 0.808511 (-2510 3360);
PAINT ORANGE (-2510 3360);
FORCEPROP 2 LASTPIN (-2500 3300) $PN 11
J 2
(-2510 3310);
DISPLAY 0.808511 (-2510 3310);
PAINT ORANGE (-2510 3310);
FORCEPROP 1 LAST VALUE PCA9554PWR-GP
J 0
(-2325 3150);
DISPLAY 0.617021 (-2325 3150);
PAINT GREEN (-2325 3150);
FORCEPROP 1 LAST PACK_TYPE DISCRET-G1
J 0
(-2150 3500);
DISPLAY 0.617021 (-2150 3500);
PAINT GREEN (-2150 3500);
DISPLAY INVISIBLE (-2150 3500);
FORCEPROP 2 LAST SEC 1
J 0
(-2350 3875);
DISPLAY 0.680851 (-2350 3875);
PAINT MONO (-2350 3875);
DISPLAY INVISIBLE (-2350 3875);
FORCEPROP 2 LAST SEC_TYPE DISCRET-G1
J 0
(-2350 3875);
DISPLAY 1.021277 (-2350 3875);
PAINT ORANGE (-2350 3875);
DISPLAY INVISIBLE (-2350 3875);
FORCEPROP 1 LAST CDS_LMAN_SYM_OUTLINE -200,300,200,-300
J 0
(-2150 3500);
DISPLAY 0.468085 (-2150 3500);
PAINT GREEN (-2150 3500);
DISPLAY INVISIBLE (-2150 3500);
FORCEPROP 1 LAST PATH I97
J 0
(-2150 3740);
DISPLAY 0.617021 (-2150 3740);
PAINT GREEN (-2150 3740);
DISPLAY INVISIBLE (-2150 3740);
FORCEPROP 2 LAST CDS_LIB w_hdl
J 0
(-2150 3500);
DISPLAY INVISIBLE (-2150 3500);
FORCEPROP 1 LAST PART_NUMBER 71.09554.C0W
J 0
(-2150 3261);
DISPLAY 0.617021 (-2150 3261);
PAINT GREEN (-2150 3261);
DISPLAY INVISIBLE (-2150 3261);
FORCEADD OFFPAGE..3
(-850 3450);
FORCEPROP 2 LAST $XR0 167 
J 0
(-636 3450);
DISPLAY 0.638298 (-636 3450);
PAINT MONO (-636 3450);
FORCEPROP 2 LAST $XR1 184 
J 0
(-516 3450);
DISPLAY 0.638298 (-516 3450);
PAINT MONO (-516 3450);
FORCEPROP 2 LAST $XR2 191 
J 0
(-396 3450);
DISPLAY 0.638298 (-396 3450);
PAINT MONO (-396 3450);
FORCEPROP 1 LAST COMMENT_BODY TRUE
J 0
(-900 3350);
DISPLAY 0.872340 (-900 3350);
PAINT GREEN (-900 3350);
DISPLAY INVISIBLE (-900 3350);
FORCEPROP 1 LAST OFFPAGE TRUE
J 0
(-525 3325);
DISPLAY 0.872340 (-525 3325);
PAINT GREEN (-525 3325);
DISPLAY INVISIBLE (-525 3325);
FORCEPROP 2 LAST CDS_LIB mstr_standard
J 0
(-850 3450);
PAINT MONO (-850 3450);
DISPLAY INVISIBLE (-850 3450);
FORCEPROP 2 LAST PATH I99
J 0
(-375 3500);
DISPLAY 1.021277 (-375 3500);
PAINT ORANGE (-375 3500);
DISPLAY INVISIBLE (-375 3500);
FORCEADD DNS..2
(-6545 920);
PAINT RED (-6545 920);
FORCEPROP 1 LAST COMMENT_BODY TRUE
R 1
J 0
(-6470 695);
DISPLAY 0.872340 (-6470 695);
PAINT GREEN (-6470 695);
DISPLAY INVISIBLE (-6470 695);
FORCEPROP 2 LAST CDS_LIB mstr_misc
J 0
(-6545 920);
PAINT ORANGE (-6545 920);
DISPLAY INVISIBLE (-6545 920);
FORCEADD DNS..2
(-7395 1595);
PAINT RED (-7395 1595);
FORCEPROP 1 LAST COMMENT_BODY TRUE
R 1
J 0
(-7320 1370);
DISPLAY 0.872340 (-7320 1370);
PAINT GREEN (-7320 1370);
DISPLAY INVISIBLE (-7320 1370);
FORCEPROP 2 LAST CDS_LIB mstr_misc
J 0
(-7395 1595);
PAINT ORANGE (-7395 1595);
DISPLAY INVISIBLE (-7395 1595);
FORCEADD DNS..2
(-1645 1795);
PAINT RED (-1645 1795);
FORCEPROP 1 LAST COMMENT_BODY TRUE
R 1
J 0
(-1570 1570);
DISPLAY 0.872340 (-1570 1570);
PAINT GREEN (-1570 1570);
DISPLAY INVISIBLE (-1570 1570);
FORCEPROP 2 LAST CDS_LIB mstr_misc
J 0
(-1645 1795);
PAINT MONO (-1645 1795);
DISPLAY INVISIBLE (-1645 1795);
FORCEADD DNS..2
(-6245 920);
PAINT RED (-6245 920);
FORCEPROP 1 LAST COMMENT_BODY TRUE
R 1
J 0
(-6170 695);
DISPLAY 0.872340 (-6170 695);
PAINT GREEN (-6170 695);
DISPLAY INVISIBLE (-6170 695);
FORCEPROP 2 LAST CDS_LIB mstr_misc
J 0
(-6245 920);
PAINT ORANGE (-6245 920);
DISPLAY INVISIBLE (-6245 920);
FORCEADD DNS..2
(-1995 2345);
PAINT RED (-1995 2345);
FORCEPROP 2 LAST CDS_LIB mstr_misc
J 0
(-1995 2345);
PAINT MONO (-1995 2345);
DISPLAY INVISIBLE (-1995 2345);
FORCEPROP 1 LAST COMMENT_BODY TRUE
R 1
J 0
(-1920 2120);
DISPLAY 0.872340 (-1920 2120);
PAINT GREEN (-1920 2120);
DISPLAY INVISIBLE (-1920 2120);
FORCEADD DNS..2
(-2345 2345);
PAINT RED (-2345 2345);
FORCEPROP 2 LAST CDS_LIB mstr_misc
J 0
(-2345 2345);
PAINT MONO (-2345 2345);
DISPLAY INVISIBLE (-2345 2345);
FORCEPROP 1 LAST COMMENT_BODY TRUE
R 1
J 0
(-2270 2120);
DISPLAY 0.872340 (-2270 2120);
PAINT GREEN (-2270 2120);
DISPLAY INVISIBLE (-2270 2120);
FORCEADD INTEL_CORP_BPAGE..1
(0 0);
FORCEPROP 1 LAST CDS_CON_LAST_MODIFIED Fri Jun 16 17:49:01 2017
J 0
(-1425 325);
DISPLAY 1.361702 (-1425 325);
PAINT GREEN (-1425 325);
DISPLAY INVISIBLE (-1425 325);
FORCEPROP 1 LAST CUSTOM_TXT_CDS <CURRENT_DESIGN_SHEET> OF <TOTAL_DESIGN_SHEETS>
J 0
(-500 25);
PAINT ORANGE (-500 25);
FORCEPROP 1 LAST CUSTOM_TXT_CDS <CON_LAST_MODIFIED>
J 0
(-4000 100);
PAINT ORANGE (-4000 100);
FORCEPROP 2 LAST CUSTOM_TXT_CDS <XR_PAGE_TITLE>
J 0
(-7890 5250);
DISPLAY 0.638298 (-7890 5250);
PAINT PINK (-7890 5250);
DISPLAY INVISIBLE (-7890 5250);
FORCEPROP 1 LAST SCH_TITLE BOARD AND SKU ID STRAPS
J 0
(-7950 50);
DISPLAY 1.212766 (-7950 50);
PAINT ORANGE (-7950 50);
FORCEPROP 2 LAST CDS_XR_PAGE_TITLE CR-164 : @BASEBOARD_FAB2_LIB.BASEBOARD_FAB2(SCH_1):PAGE164
J 0
(-7890 5250);
DISPLAY 0.638298 (-7890 5250);
PAINT PINK (-7890 5250);
DISPLAY INVISIBLE (-7890 5250);
FORCEPROP 2 LAST PAGE_BORDER TRUE
J 0
(-7890 5250);
DISPLAY 0.851064 (-7890 5250);
PAINT PINK (-7890 5250);
DISPLAY INVISIBLE (-7890 5250);
FORCEPROP 2 LAST CDS_LIB mstr_symbols
J 0
(0 0);
DISPLAY 1.361702 (0 0);
PAINT ORANGE (0 0);
DISPLAY INVISIBLE (0 0);
FORCEPROP 1 LAST COMMENT_BODY TRUE
J 0
(12 12);
DISPLAY 0.617021 (12 12);
PAINT GREEN (12 12);
DISPLAY INVISIBLE (12 12);
WIRE 16 -1 (-7750 1600)(-7750 1700);
WIRE 16 -1 (-7750 1400)(-7750 1600);
WIRE 16 -1 (-7750 1600)(-7500 1600);
WIRE 16 -1 (-7750 1200)(-7750 1400);
WIRE 16 -1 (-7750 1400)(-7500 1400);
WIRE 16 -1 (-7750 1200)(-7500 1200);
WIRE 16 -1 (-7525 4600)(-7525 4475);
WIRE 16 -1 (-7525 4475)(-7525 4275);
WIRE 16 -1 (-7525 4475)(-7275 4475);
WIRE 16 -1 (-7525 4075)(-7525 4275);
WIRE 16 -1 (-7525 4275)(-7275 4275);
WIRE 16 -1 (-7525 3875)(-7525 4075);
WIRE 16 -1 (-7525 4075)(-7275 4075);
WIRE 16 -1 (-7525 3675)(-7525 3875);
WIRE 16 -1 (-7525 3875)(-7275 3875);
WIRE 16 -1 (-7525 3675)(-7275 3675);
WIRE 16 -1 (-6625 3100)(-6625 3125);
WIRE 16 -1 (-6325 3125)(-6625 3125);
WIRE 16 -1 (-6625 3125)(-6625 3250);
WIRE 16 -1 (-6025 3125)(-6325 3125);
WIRE 16 -1 (-6325 3125)(-6325 3250);
WIRE 16 -1 (-5725 3125)(-6025 3125);
WIRE 16 -1 (-6025 3250)(-6025 3125);
WIRE 16 -1 (-5425 3125)(-5725 3125);
WIRE 16 -1 (-5725 3250)(-5725 3125);
WIRE 16 -1 (-5425 3250)(-5425 3125);
WIRE 16 -1 (-1750 3225)(-1750 3250);
WIRE 16 -1 (-1800 3250)(-1750 3250);
WIRE 16 -1 (-3400 4100)(-3400 4050);
WIRE 16 -1 (-3400 4050)(-2600 4050);
WIRE 16 -1 (-3400 4050)(-3400 4000);
WIRE 16 -1 (-2600 4050)(-2600 3750);
WIRE 16 -1 (-2600 3750)(-2500 3750);
WIRE 16 -1 (-3400 3800)(-3400 3750);
WIRE 16 -1 (-2350 2550)(-2350 2600);
WIRE 16 -1 (-2000 2550)(-2350 2550);
WIRE 16 -1 (-2350 2450)(-2350 2550);
WIRE 16 -1 (-1650 2550)(-2000 2550);
WIRE 16 -1 (-2000 2450)(-2000 2550);
WIRE 16 -1 (-1650 2450)(-1650 2550);
WIRE 16 -1 (-1650 1650)(-1650 1700);
WIRE 16 -1 (-2000 1650)(-2000 1700);
WIRE 16 -1 (-2350 1650)(-2350 1700);
WIRE 16 -1 (-1000 3850)(-1000 3900);
WIRE 16 -1 (-6850 675)(-6850 750);
WIRE 16 -1 (-6550 750)(-6850 750);
WIRE 16 -1 (-6850 825)(-6850 750);
WIRE 16 -1 (-6250 750)(-6550 750);
WIRE 16 -1 (-6550 825)(-6550 750);
WIRE 16 -1 (-6250 825)(-6250 750);
WIRE 16 -1 (-6025 3450)(-6025 4075);
WIRE 16 -1 (-6025 4075)(-4925 4075);
FORCEPROP 2 LAST SIG_NAME FM_BOARD_SKU_ID2
J 0
(-5400 4085);
DISPLAY 0.617021 (-5400 4085);
PAINT ORANGE (-5400 4085);
WIRE 16 -1 (-7075 4075)(-6025 4075);
WIRE 16 -1 (-5425 3450)(-5425 3675);
WIRE 16 -1 (-5425 3675)(-4925 3675);
WIRE 16 -1 (-7075 3675)(-5425 3675);
FORCEPROP 2 LAST SIG_NAME FM_BOARD_SKU_ID0
J 0
(-5400 3685);
DISPLAY 0.617021 (-5400 3685);
PAINT ORANGE (-5400 3685);
WIRE 3 682 (-3700 2900)(-3600 2900);
WIRE 3 682 (-3700 3050)(-3700 2900);
WIRE 3 682 (-3650 3000)(-3600 3000);
WIRE 3 682 (-3650 3050)(-3650 3000);
WIRE 3 682 (-3650 3050)(-3700 3050);
WIRE 3 682 (-3650 3350)(-3650 3050);
WIRE 3 682 (-3600 3350)(-3650 3350);
WIRE 3 2175 (-7800 2950)(-3850 2950);
WIRE 3 2175 (-3850 4750)(-3850 2950);
WIRE 3 2175 (-7800 4750)(-7800 2950);
WIRE 3 2175 (-7800 4750)(-3850 4750);
WIRE 3 682 (-3750 4300)(-3750 1450);
WIRE 3 682 (-150 4300)(-3750 4300);
WIRE 3 682 (-3750 1450)(-150 1450);
WIRE 3 682 (-150 1450)(-150 4300);
WIRE 16 -1 (-5850 450)(-3900 450);
WIRE 16 -1 (-5850 575)(-5850 450);
WIRE 16 -1 (-3900 450)(-3900 325);
WIRE 16 -1 (-5850 450)(-5850 325);
WIRE 16 -1 (-5850 325)(-4950 325);
WIRE 16 -1 (-4950 325)(-3900 325);
WIRE 16 -1 (-5850 575)(-3900 575);
WIRE 16 -1 (-3900 450)(-3900 575);
WIRE 16 -1 (-5850 725)(-5850 575);
WIRE 16 -1 (-5850 725)(-3900 725);
WIRE 16 -1 (-3900 575)(-3900 725);
WIRE 16 -1 (-5850 850)(-5850 725);
WIRE 16 -1 (-5850 950)(-5850 850);
WIRE 16 -1 (-4950 950)(-5850 950);
WIRE 16 -1 (-4950 950)(-4950 325);
WIRE 16 -1 (-3900 950)(-4950 950);
WIRE 16 -1 (-5850 850)(-3900 850);
WIRE 16 -1 (-3900 725)(-3900 850);
WIRE 16 -1 (-3900 850)(-3900 950);
WIRE 16 -1 (-2350 1900)(-2350 2100);
WIRE 16 -1 (-2350 2100)(-2350 2250);
WIRE 16 -1 (-1300 2100)(-2350 2100);
FORCEPROP 2 LAST SIG_NAME PCA9554_A2
J 0
(-1610 2110);
DISPLAY 0.680851 (-1610 2110);
PAINT ORANGE (-1610 2110);
FORCEPROP 2 LASTPROP $XR0 164 
J 0
(-1270 2100);
DISPLAY 0.638298 (-1270 2100);
PAINT MONO (-1270 2100);
WIRE 16 -1 (-6550 1025)(-6550 1400);
WIRE 16 -1 (-6550 1400)(-5725 1400);
WIRE 16 -1 (-7300 1400)(-6550 1400);
FORCEPROP 2 LAST SIG_NAME FM_BOARD_REV_ID1
J 2
(-5825 1410);
DISPLAY 0.617021 (-5825 1410);
PAINT ORANGE (-5825 1410);
WIRE 16 -1 (-6250 1025)(-6250 1200);
WIRE 16 -1 (-6250 1200)(-5725 1200);
WIRE 16 -1 (-7300 1200)(-6250 1200);
FORCEPROP 2 LAST SIG_NAME FM_BOARD_REV_ID0
J 2
(-5825 1210);
DISPLAY 0.617021 (-5825 1210);
PAINT ORANGE (-5825 1210);
WIRE 3 682 (-300 3450)(-250 3450);
WIRE 3 682 (-250 3400)(-300 3400);
WIRE 3 682 (-250 3450)(-250 3400);
WIRE 3 682 (-250 3400)(-200 3400);
WIRE 3 682 (-200 3400)(-200 3300);
WIRE 3 682 (-200 3300)(-250 3300);
WIRE 16 -1 (-1000 3550)(-1800 3550);
FORCEPROP 2 LAST SIG_NAME PCA9554_INT_N
J 0
(-1635 3560);
DISPLAY 0.680851 (-1635 3560);
PAINT ORANGE (-1635 3560);
FORCEPROP 2 LASTPROP $XRERR UNIQUE?
J 0
(-1875 3560);
DISPLAY 0.638298 (-1875 3560);
PAINT MONO (-1875 3560);
DISPLAY INVISIBLE (-1875 3560);
WIRE 16 -1 (-1000 3650)(-1000 3550);
WIRE 16 -1 (-1325 3650)(-1800 3650);
FORCEPROP 2 LAST SIG_NAME PCA9554_A2
J 0
(-1735 3660);
DISPLAY 0.680851 (-1735 3660);
PAINT ORANGE (-1735 3660);
FORCEPROP 2 LASTPROP $XR0 164 
J 0
(-1295 3650);
DISPLAY 0.638298 (-1295 3650);
PAINT MONO (-1295 3650);
WIRE 16 -1 (-1325 3700)(-1800 3700);
FORCEPROP 2 LAST SIG_NAME PCA9554_A1
J 0
(-1735 3710);
DISPLAY 0.680851 (-1735 3710);
PAINT ORANGE (-1735 3710);
FORCEPROP 2 LASTPROP $XR0 164 
J 0
(-1295 3700);
DISPLAY 0.638298 (-1295 3700);
PAINT MONO (-1295 3700);
WIRE 16 -1 (-3100 3450)(-2500 3450);
FORCEPROP 2 LAST SIG_NAME FM_CPU_BMC_INIT
J 0
(-3060 3460);
DISPLAY 0.638298 (-3060 3460);
PAINT ORANGE (-3060 3460);
WIRE 16 -1 (-3100 3500)(-2500 3500);
FORCEPROP 2 LAST SIG_NAME FM_MB_SLOT_ID2
J 0
(-3060 3510);
DISPLAY 0.638298 (-3060 3510);
PAINT ORANGE (-3060 3510);
WIRE 16 -1 (-900 3400)(-1800 3400);
FORCEPROP 2 LAST SIG_NAME SMB_SENSOR_STBY_LVC3_SCL
J 0
(-1635 3410);
DISPLAY 0.680851 (-1635 3410);
PAINT ORANGE (-1635 3410);
WIRE 16 -1 (-1325 3750)(-1800 3750);
FORCEPROP 2 LAST SIG_NAME PCA9554_A0
J 0
(-1735 3760);
DISPLAY 0.680851 (-1735 3760);
PAINT ORANGE (-1735 3760);
FORCEPROP 2 LASTPROP $XR0 164 
J 0
(-1295 3750);
DISPLAY 0.638298 (-1295 3750);
PAINT MONO (-1295 3750);
WIRE 16 -1 (-1650 1900)(-1650 2000);
WIRE 16 -1 (-1650 2250)(-1650 2000);
WIRE 16 -1 (-1300 2000)(-1650 2000);
FORCEPROP 2 LAST SIG_NAME PCA9554_A0
J 0
(-1610 2010);
DISPLAY 0.680851 (-1610 2010);
PAINT ORANGE (-1610 2010);
FORCEPROP 2 LASTPROP $XR0 164 
J 0
(-1270 2000);
DISPLAY 0.638298 (-1270 2000);
PAINT MONO (-1270 2000);
WIRE 16 -1 (-900 3450)(-1800 3450);
FORCEPROP 2 LAST SIG_NAME SMB_SENSOR_STBY_LVC3_SDA
J 0
(-1635 3460);
DISPLAY 0.680851 (-1635 3460);
PAINT ORANGE (-1635 3460);
WIRE 16 -1 (-2500 3550)(-3100 3550);
FORCEPROP 2 LAST SIG_NAME FM_MB_SLOT_ID1
J 0
(-3060 3560);
DISPLAY 0.638298 (-3060 3560);
PAINT ORANGE (-3060 3560);
WIRE 16 -1 (-3100 3600)(-2500 3600);
FORCEPROP 2 LAST SIG_NAME FM_MB_SLOT_ID0
J 0
(-3060 3610);
DISPLAY 0.638298 (-3060 3610);
PAINT ORANGE (-3060 3610);
WIRE 16 -1 (-2000 1900)(-2000 2050);
WIRE 16 -1 (-2000 2250)(-2000 2050);
WIRE 16 -1 (-1300 2050)(-2000 2050);
FORCEPROP 2 LAST SIG_NAME PCA9554_A1
J 0
(-1610 2060);
DISPLAY 0.680851 (-1610 2060);
PAINT ORANGE (-1610 2060);
FORCEPROP 2 LASTPROP $XR0 164 
J 0
(-1270 2050);
DISPLAY 0.638298 (-1270 2050);
PAINT MONO (-1270 2050);
WIRE 16 -1 (-6850 1025)(-6850 1600);
WIRE 16 -1 (-6850 1600)(-5725 1600);
FORCEPROP 2 LAST SIG_NAME FM_BOARD_REV_ID2
J 2
(-5825 1610);
DISPLAY 0.617021 (-5825 1610);
PAINT ORANGE (-5825 1610);
WIRE 16 -1 (-7300 1600)(-6850 1600);
WIRE 16 -1 (-5725 3450)(-5725 3875);
WIRE 16 -1 (-5725 3875)(-4925 3875);
WIRE 16 -1 (-7075 3875)(-5725 3875);
FORCEPROP 2 LAST SIG_NAME FM_BOARD_SKU_ID1
J 0
(-5400 3885);
DISPLAY 0.617021 (-5400 3885);
PAINT ORANGE (-5400 3885);
WIRE 16 -1 (-7075 4275)(-6325 4275);
WIRE 16 -1 (-6325 4275)(-4925 4275);
FORCEPROP 2 LAST SIG_NAME FM_BOARD_SKU_ID3
J 0
(-5400 4285);
DISPLAY 0.617021 (-5400 4285);
PAINT ORANGE (-5400 4285);
WIRE 16 -1 (-6325 3450)(-6325 4275);
WIRE 16 -1 (-6625 3450)(-6625 4475);
WIRE 16 -1 (-6625 4475)(-7075 4475);
WIRE 16 -1 (-5000 4475)(-6625 4475);
FORCEPROP 0 LAST SIG_NAME FM_BOARD_SKU_ID4
J 0
(-5400 4485);
DISPLAY 0.617021 (-5400 4485);
PAINT ORANGE (-5400 4485);
DOT 1 (-6025 3125);
DOT 1 (-6325 4275);
DOT 1 (-5725 3875);
DOT 1 (-6025 4075);
DOT 1 (-5725 3125);
DOT 1 (-6550 1400);
DOT 1 (-5850 725);
DOT 1 (-2350 2100);
DOT 1 (-250 3400);
DOT 1 (-2350 2550);
DOT 1 (-3650 3050);
DOT 1 (-3400 4050);
DOT 1 (-1650 2000);
DOT 1 (-2000 2050);
DOT 1 (-2000 2550);
DOT 1 (-5850 450);
DOT 1 (-4950 325);
DOT 1 (-4950 950);
DOT 1 (-3900 450);
DOT 1 (-3900 850);
DOT 1 (-5850 575);
DOT 1 (-7750 1400);
DOT 1 (-6850 750);
DOT 1 (-6550 750);
DOT 1 (-6850 1600);
DOT 1 (-6250 1200);
DOT 1 (-7750 1600);
DOT 1 (-6625 3125);
DOT 1 (-6325 3125);
DOT 1 (-7525 3875);
DOT 1 (-7525 4075);
DOT 1 (-7525 4475);
DOT 1 (-6625 4475);
DOT 1 (-5425 3675);
DOT 1 (-7525 4275);
DOT 1 (-5850 850);
DOT 1 (-3900 725);
DOT 1 (-3900 575);
FORCENOTE
TP FAB3 ADD TCA9555 0920
(-3750 1350) 0;
DISPLAY LEFT (-3750 1350);
DISPLAY 1.021277 (-3750 1350);
PAINT RED (-3750 1350);
FORCENOTE
TP FAB3 CHANGE TCA9555 TO PCA9554 0920
(-3750 1275) 0;
DISPLAY LEFT (-3750 1275);
DISPLAY 1.021277 (-3750 1275);
PAINT RED (-3750 1275);
FORCENOTE
TP FAB4 NOPOP R1U24, AND POP R1U17 20170206
(-7800 4800) 0;
DISPLAY LEFT (-7800 4800);
DISPLAY 0.638298 (-7800 4800);
PAINT RED (-7800 4800);
FORCENOTE
TP FAB1 CONFIG FM_BOARD_SKU_ID<4:0> TO 00001.
(-7800 4900) 0;
DISPLAY LEFT (-7800 4900);
DISPLAY 0.638298 (-7800 4900);
PAINT RED (-7800 4900);
FORCENOTE
TP FAB1 CHANGE CONFIGURATION 0310
(-7800 4850) 0;
DISPLAY LEFT (-7800 4850);
DISPLAY 0.638298 (-7800 4850);
PAINT RED (-7800 4850);
FORCENOTE
TP FAB3 NOPOP R6W42, R6W43; POP R6W45, R6W46 0922
(-1900 1525) 0;
DISPLAY LEFT (-1900 1525);
DISPLAY 0.638298 (-1900 1525);
PAINT RED (-1900 1525);
FORCENOTE
TP FAB4 POP R1T4 AND NOPOP R1T10 20170116
(-6050 1025) 0;
DISPLAY LEFT (-6050 1025);
DISPLAY 0.638298 (-6050 1025);
PAINT RED (-6050 1025);
FORCENOTE
FM_BOARD_REV_ID[2:0]
(-5800 875) 0;
DISPLAY LEFT (-5800 875);
DISPLAY 1.021277 (-5800 875);
PAINT PURPLE (-5800 875);
FORCENOTE
TP FAB3 RECONNECT 0922
(-700 3275) 0;
DISPLAY LEFT (-700 3275);
DISPLAY 0.638298 (-700 3275);
PAINT RED (-700 3275);
FORCENOTE
TP FAB3 RECONNECT 0922
(-3575 2875) 0;
DISPLAY LEFT (-3575 2875);
DISPLAY 0.638298 (-3575 2875);
PAINT RED (-3575 2875);
FORCENOTE
1
(-5500 375) 0;
DISPLAY LEFT (-5500 375);
DISPLAY 1.021277 (-5500 375);
PAINT PURPLE (-5500 375);
FORCENOTE
1
(-5500 500) 0;
DISPLAY LEFT (-5500 500);
DISPLAY 1.021277 (-5500 500);
PAINT PURPLE (-5500 500);
FORCENOTE
0
(-5625 375) 0;
DISPLAY LEFT (-5625 375);
DISPLAY 1.021277 (-5625 375);
PAINT PURPLE (-5625 375);
FORCENOTE
1
(-5350 375) 0;
DISPLAY LEFT (-5350 375);
DISPLAY 1.021277 (-5350 375);
PAINT PURPLE (-5350 375);
FORCENOTE
0
(-5350 500) 0;
DISPLAY LEFT (-5350 500);
DISPLAY 1.021277 (-5350 500);
PAINT PURPLE (-5350 500);
FORCENOTE
0
(-5625 500) 0;
DISPLAY LEFT (-5625 500);
DISPLAY 1.021277 (-5625 500);
PAINT PURPLE (-5625 500);
FORCENOTE
ADDRESS 0X42
(-2450 1500) 0;
DISPLAY LEFT (-2450 1500);
DISPLAY 1.021277 (-2450 1500);
PAINT PURPLE (-2450 1500);
FORCENOTE
1
(-5350 625) 0;
DISPLAY LEFT (-5350 625);
DISPLAY 1.021277 (-5350 625);
PAINT PURPLE (-5350 625);
FORCENOTE
0
(-5500 625) 0;
DISPLAY LEFT (-5500 625);
DISPLAY 1.021277 (-5500 625);
PAINT PURPLE (-5500 625);
FORCENOTE
0
(-5625 625) 0;
DISPLAY LEFT (-5625 625);
DISPLAY 1.021277 (-5625 625);
PAINT PURPLE (-5625 625);
FORCENOTE
0
(-5350 750) 0;
DISPLAY LEFT (-5350 750);
DISPLAY 1.021277 (-5350 750);
PAINT PURPLE (-5350 750);
FORCENOTE
0
(-5500 750) 0;
DISPLAY LEFT (-5500 750);
DISPLAY 1.021277 (-5500 750);
PAINT PURPLE (-5500 750);
FORCENOTE
0
(-5625 750) 0;
DISPLAY LEFT (-5625 750);
DISPLAY 1.021277 (-5625 750);
PAINT PURPLE (-5625 750);
FORCENOTE
FAB2 (EVT2)
(-4850 625) 0;
DISPLAY LEFT (-4850 625);
DISPLAY 1.021277 (-4850 625);
PAINT PURPLE (-4850 625);
FORCENOTE
FAB1 (POWER ON/EVT)
(-4850 750) 0;
DISPLAY LEFT (-4850 750);
DISPLAY 1.021277 (-4850 750);
PAINT PURPLE (-4850 750);
FORCENOTE
TP FAB3 POP R1T6 AND NOPOP R1T12 0803
(-6050 1075) 0;
DISPLAY LEFT (-6050 1075);
DISPLAY 0.638298 (-6050 1075);
PAINT RED (-6050 1075);
FORCENOTE
REV
(-4850 875) 0;
DISPLAY LEFT (-4850 875);
DISPLAY 1.021277 (-4850 875);
PAINT PURPLE (-4850 875);
FORCENOTE
FAB3 (EVT3, PRE-DVT) 
(-4850 500) 0;
DISPLAY LEFT (-4850 500);
DISPLAY 1.021277 (-4850 500);
PAINT PURPLE (-4850 500);
FORCENOTE
FAB4 (DVT)
(-4850 375) 0;
DISPLAY LEFT (-4850 375);
DISPLAY 1.021277 (-4850 375);
PAINT PURPLE (-4850 375);
FORCENOTE
$CDS_IMAGE|123.JPG|4000|440
(-5850 2675) 0;
DISPLAY LEFT (-5850 2675);
QUIT
